G04 ================== begin FILE IDENTIFICATION RECORD ==================*
G04 Layout Name:  12432-1.brd*
G04 Film Name:    L4VCC*
G04 File Format:  Gerber RS274X*
G04 File Origin:  Cadence Allegro 16.2-S037*
G04 Origin Date:  Wed Oct 17 11:00:06 2012*
G04 *
G04 Layer:  VIA CLASS/L4VCC*
G04 Layer:  PIN/L4VCC*
G04 Layer:  PACKAGE GEOMETRY/PWRVCC*
G04 Layer:  ETCH/L4VCC*
G04 Layer:  DRAWING FORMAT/LAYER_PCB_STORY*
G04 Layer:  DRAWING FORMAT/LAYER_L4VCC*
G04 *
G04 Offset:    (0.00 0.00)*
G04 Mirror:    No*
G04 Mode:      Negative*
G04 Rotation:  0*
G04 FullContactRelief:  No*
G04 UndefLineWidth:     6.00*
G04 ================== end FILE IDENTIFICATION RECORD ====================*
%FSLAX35Y35*MOIN*%
%IR0*IPPOS*OFA0.00000B0.00000*MIA0B0*SFA1.00000B1.00000*%
%ADD16O,.115X.072*%
%ADD14C,.032*%
%ADD11C,.036*%
%AMMACRO20*
4,1,15,.00398,.00044,
.003999,.000208,
.004004,-.000025,
.003996,-.000258,
.00398,-.00044,
.00483,-.00129,
.004897,-.001007,
.004947,-.000721,
.004981,-.000432,
.004997,-.000141,
.004997,.000149,
.00498,.00044,
.004946,.000729,
.004895,.001015,
.00483,.00129,
.00398,.00044,
90.*
4,1,15,.00044,-.00398,
.000208,-.003999,
-.000025,-.004004,
-.000258,-.003996,
-.00044,-.00398,
-.00129,-.00483,
-.001007,-.004897,
-.000721,-.004947,
-.000432,-.004981,
-.000141,-.004997,
.000149,-.004997,
.00044,-.00498,
.000729,-.004946,
.001015,-.004895,
.00129,-.00483,
.00044,-.00398,
90.*
4,1,15,-.00398,-.00044,
-.003999,-.000208,
-.004004,.000025,
-.003996,.000258,
-.00398,.00044,
-.00483,.00129,
-.004897,.001007,
-.004947,.000721,
-.004981,.000432,
-.004997,.000141,
-.004997,-.000149,
-.00498,-.00044,
-.004946,-.000729,
-.004895,-.001015,
-.00483,-.00129,
-.00398,-.00044,
90.*
4,1,15,-.00044,.00398,
-.000208,.003999,
.000025,.004004,
.000258,.003996,
.00044,.00398,
.00129,.00483,
.001007,.004897,
.000721,.004947,
.000432,.004981,
.000141,.004997,
-.000149,.004997,
-.00044,.00498,
-.000729,.004946,
-.001015,.004895,
-.00129,.00483,
-.00044,.00398,
90.*
%
%ADD20MACRO20*%
%AMMACRO15*
4,1,15,.00398,.00044,
.003999,.000208,
.004004,-.000025,
.003996,-.000258,
.00398,-.00044,
.00483,-.00129,
.004897,-.001007,
.004947,-.000721,
.004981,-.000432,
.004997,-.000141,
.004997,.000149,
.00498,.00044,
.004946,.000729,
.004895,.001015,
.00483,.00129,
.00398,.00044,
0.0*
4,1,15,.00044,-.00398,
.000208,-.003999,
-.000025,-.004004,
-.000258,-.003996,
-.00044,-.00398,
-.00129,-.00483,
-.001007,-.004897,
-.000721,-.004947,
-.000432,-.004981,
-.000141,-.004997,
.000149,-.004997,
.00044,-.00498,
.000729,-.004946,
.001015,-.004895,
.00129,-.00483,
.00044,-.00398,
0.0*
4,1,15,-.00398,-.00044,
-.003999,-.000208,
-.004004,.000025,
-.003996,.000258,
-.00398,.00044,
-.00483,.00129,
-.004897,.001007,
-.004947,.000721,
-.004981,.000432,
-.004997,.000141,
-.004997,-.000149,
-.00498,-.00044,
-.004946,-.000729,
-.004895,-.001015,
-.00483,-.00129,
-.00398,-.00044,
0.0*
4,1,15,-.00044,.00398,
-.000208,.003999,
.000025,.004004,
.000258,.003996,
.00044,.00398,
.00129,.00483,
.001007,.004897,
.000721,.004947,
.000432,.004981,
.000141,.004997,
-.000149,.004997,
-.00044,.00498,
-.000729,.004946,
-.001015,.004895,
-.00129,.00483,
-.00044,.00398,
0.0*
%
%ADD15MACRO15*%
%ADD17C,.101*%
%ADD10C,.114*%
%ADD12C,.18*%
%ADD13C,.119*%
%ADD22C,.174*%
%ADD18C,.197*%
%AMMACRO21*
4,1,15,.00398,.00044,
.003999,.000208,
.004004,-.000025,
.003996,-.000258,
.00398,-.00044,
.00483,-.00129,
.004897,-.001007,
.004947,-.000721,
.004981,-.000432,
.004997,-.000141,
.004997,.000149,
.00498,.00044,
.004946,.000729,
.004895,.001015,
.00483,.00129,
.00398,.00044,
270.*
4,1,15,.00044,-.00398,
.000208,-.003999,
-.000025,-.004004,
-.000258,-.003996,
-.00044,-.00398,
-.00129,-.00483,
-.001007,-.004897,
-.000721,-.004947,
-.000432,-.004981,
-.000141,-.004997,
.000149,-.004997,
.00044,-.00498,
.000729,-.004946,
.001015,-.004895,
.00129,-.00483,
.00044,-.00398,
270.*
4,1,15,-.00398,-.00044,
-.003999,-.000208,
-.004004,.000025,
-.003996,.000258,
-.00398,.00044,
-.00483,.00129,
-.004897,.001007,
-.004947,.000721,
-.004981,.000432,
-.004997,.000141,
-.004997,-.000149,
-.00498,-.00044,
-.004946,-.000729,
-.004895,-.001015,
-.00483,-.00129,
-.00398,-.00044,
270.*
4,1,15,-.00044,.00398,
-.000208,.003999,
.000025,.004004,
.000258,.003996,
.00044,.00398,
.00129,.00483,
.001007,.004897,
.000721,.004947,
.000432,.004981,
.000141,.004997,
-.000149,.004997,
-.00044,.00498,
-.000729,.004946,
-.001015,.004895,
-.00129,.00483,
-.00044,.00398,
270.*
%
%ADD21MACRO21*%
%AMMACRO19*
4,1,15,.00398,.00044,
.003999,.000208,
.004004,-.000025,
.003996,-.000258,
.00398,-.00044,
.00483,-.00129,
.004897,-.001007,
.004947,-.000721,
.004981,-.000432,
.004997,-.000141,
.004997,.000149,
.00498,.00044,
.004946,.000729,
.004895,.001015,
.00483,.00129,
.00398,.00044,
180.*
4,1,15,.00044,-.00398,
.000208,-.003999,
-.000025,-.004004,
-.000258,-.003996,
-.00044,-.00398,
-.00129,-.00483,
-.001007,-.004897,
-.000721,-.004947,
-.000432,-.004981,
-.000141,-.004997,
.000149,-.004997,
.00044,-.00498,
.000729,-.004946,
.001015,-.004895,
.00129,-.00483,
.00044,-.00398,
180.*
4,1,15,-.00398,-.00044,
-.003999,-.000208,
-.004004,.000025,
-.003996,.000258,
-.00398,.00044,
-.00483,.00129,
-.004897,.001007,
-.004947,.000721,
-.004981,.000432,
-.004997,.000141,
-.004997,-.000149,
-.00498,-.00044,
-.004946,-.000729,
-.004895,-.001015,
-.00483,-.00129,
-.00398,-.00044,
180.*
4,1,15,-.00044,.00398,
-.000208,.003999,
.000025,.004004,
.000258,.003996,
.00044,.00398,
.00129,.00483,
.001007,.004897,
.000721,.004947,
.000432,.004981,
.000141,.004997,
-.000149,.004997,
-.00044,.00498,
-.000729,.004946,
-.001015,.004895,
-.00129,.00483,
-.00044,.00398,
180.*
%
%ADD19MACRO19*%
%ADD23C,.02*%
%ADD24C,.006*%
%ADD26C,.09706*%
%ADD27C,.11506*%
%ADD25C,.17006*%
G75*
%LPD*%
G75*
G36*
G01X-6000Y-6000D02*
X1039465D01*
Y1998126D01*
X-6000D01*
Y-6000D01*
G37*
%LPC*%
G75*
G36*
G01X5182Y833516D02*
X3004Y835694D01*
Y1392653D01*
X5182Y1394831D01*
X19882D01*
G03Y1408319I0J6744D01*
G01X5182D01*
X3004Y1410497D01*
Y1802101D01*
X5182Y1804279D01*
X19882D01*
G03Y1817768I0J6744D01*
G01X5182D01*
X3004Y1819946D01*
Y1988189D01*
G02X3937Y1989122I933J0D01*
G01X1029528D01*
G02X1030461Y1988189I0J-933D01*
G01Y1686599D01*
X1028283Y1684421D01*
X1023228D01*
G03X1016287Y1677480I0J-6941D01*
G01Y1621265D01*
X1014109Y1619087D01*
X989744D01*
G03Y1608866I0J-5110D01*
G01X1014109D01*
X1016287Y1606688D01*
Y1432756D01*
G03X1023228Y1425815I6941J0D01*
G01X1028283D01*
X1030461Y1423637D01*
Y3937D01*
G02X1029528Y3004I-933J0D01*
G01X3937D01*
G02X3004Y3937I0J933D01*
G01Y408401D01*
X5182Y410579D01*
X19882D01*
G03Y424067I0J6744D01*
G01X5182D01*
X3004Y426245D01*
Y817849D01*
X5182Y820027D01*
X19882D01*
G03Y833516I0J6745D01*
G01X5182D01*
G37*
%LPD*%
G75*
G36*
G01X245630Y35739D02*
X245571Y35800D01*
X139688D01*
X124249Y51239D01*
Y149861D01*
X144438Y170050D01*
X117749Y196739D01*
Y389861D01*
X123542Y395654D01*
X123527Y395755D01*
G02X126494Y398722I2572J395D01*
G01X126595Y398707D01*
X153749Y425861D01*
Y443269D01*
X153593Y443305D01*
G02Y447795I508J2245D01*
G01X153749Y447831D01*
Y473917D01*
X153588Y473949D01*
G02Y479051I512J2551D01*
G01X153749Y479083D01*
Y526652D01*
X153588Y526685D01*
G02Y531787I511J2551D01*
G01X153749Y531820D01*
Y594919D01*
X153728Y594961D01*
G02Y599291I4343J2165D01*
G01X153749Y599333D01*
Y602861D01*
X160749Y609861D01*
Y621473D01*
X160688Y621532D01*
G02Y625268I1812J1868D01*
G01X160749Y625327D01*
Y636806D01*
X160585Y636836D01*
G02Y641364I415J2264D01*
G01X160749Y641394D01*
Y645739D01*
X121749Y684739D01*
Y776361D01*
X154749Y809361D01*
Y835741D01*
X154569Y835760D01*
G02X152732Y839064I230J2290D01*
G01X152795Y839193D01*
X150749Y841239D01*
Y923361D01*
X154749Y927361D01*
Y984022D01*
X154688Y984081D01*
G02Y987819I1811J1869D01*
G01X154749Y987878D01*
Y999100D01*
X154688Y999159D01*
G02Y1006117I3383J3479D01*
G01X154749Y1006176D01*
Y1074239D01*
X112813Y1116175D01*
X112672Y1116057D01*
G02X109006Y1119723I-1673J1993D01*
G01X109124Y1119864D01*
X107749Y1121239D01*
Y1228861D01*
X154249Y1275361D01*
Y1405159D01*
X154208Y1405213D01*
G02Y1411087I3863J2937D01*
G01X154249Y1411141D01*
Y1424239D01*
X101071Y1477417D01*
X100965Y1477396D01*
G02X99625Y1481780I-466J2254D01*
G01X99749Y1481831D01*
Y1534398D01*
X99649Y1534456D01*
G02X98803Y1537594I1151J1993D01*
G03X98731Y1537866I-174J100D01*
G02X99577Y1542129I1168J1984D01*
G01X99749Y1542154D01*
Y1544356D01*
X99585Y1544386D01*
G02Y1548914I415J2264D01*
G01X99749Y1548944D01*
Y1587361D01*
X154249Y1641861D01*
Y1783739D01*
X114188Y1823800D01*
X97278D01*
X97250Y1823792D01*
G02X95950I-650J2208D01*
G01X95922Y1823800D01*
X83688D01*
X73749Y1833739D01*
Y1941861D01*
X82188Y1950300D01*
X192810D01*
X236566Y1906544D01*
G03X237249Y1906827I283J283D01*
G01Y1937861D01*
X243188Y1943800D01*
X277810D01*
X290310Y1931300D01*
X521310D01*
X551249Y1901361D01*
Y1304682D01*
X551303Y1304624D01*
G02Y1301076I-1904J-1774D01*
G01X551249Y1301018D01*
Y1295682D01*
X551303Y1295624D01*
G02Y1292076I-1904J-1774D01*
G01X551249Y1292018D01*
Y1276682D01*
X551303Y1276624D01*
G02Y1273076I-1904J-1774D01*
G01X551249Y1273018D01*
Y1268227D01*
X551260Y1268195D01*
G02Y1266505I-2461J-845D01*
G01X551249Y1266473D01*
Y1253727D01*
X551260Y1253695D01*
G02Y1252005I-2461J-845D01*
G01X551249Y1251973D01*
Y1117358D01*
X551274Y1117313D01*
G02Y1114787I-2275J-1263D01*
G01X551249Y1114742D01*
Y712335D01*
X551346Y712277D01*
G02Y707823I-1347J-2227D01*
G01X551249Y707765D01*
Y96739D01*
X540310Y85800D01*
X388310D01*
X338310Y35800D01*
X249427D01*
X249368Y35739D01*
G02X245630I-1869J1811D01*
G37*
G36*
G01X964249Y134239D02*
X907310Y77300D01*
X780688D01*
X760749Y97239D01*
Y179348D01*
G02Y184552I50J2602D01*
G01Y342748D01*
G02Y347352I29J2302D01*
G01Y734063D01*
X760745Y734083D01*
G02Y735017I2254J467D01*
G01X760749Y735037D01*
Y795232D01*
X760731Y795272D01*
G02Y797428I2368J1078D01*
G01X760749Y797468D01*
Y1092954D01*
X760581Y1092982D01*
G02Y1098118I418J2568D01*
G01X760749Y1098146D01*
Y1333623D01*
X760688Y1333681D01*
G02Y1337419I1811J1869D01*
G01X760749Y1337477D01*
Y1351123D01*
X760688Y1351181D01*
G02Y1354919I1811J1869D01*
G01X760749Y1354977D01*
Y1887832D01*
X760745Y1887851D01*
G02Y1888849I2554J499D01*
G01X760749Y1888868D01*
Y1908861D01*
X778188Y1926300D01*
X869802D01*
X869836Y1926458D01*
G02X874336I2250J-486D01*
G01X874370Y1926300D01*
X947310D01*
X964249Y1909361D01*
Y1579323D01*
X964253Y1579304D01*
G02Y1578296I-2553J-504D01*
G01X964249Y1578277D01*
Y1573520D01*
X964267Y1573480D01*
G02Y1571320I-2367J-1080D01*
G01X964249Y1571280D01*
Y1523520D01*
X964267Y1523480D01*
G02Y1521320I-2367J-1080D01*
G01X964249Y1521280D01*
Y1517468D01*
X964281Y1517419D01*
G02Y1514581I-2181J-1419D01*
G01X964249Y1514532D01*
Y1467810D01*
X964274Y1467764D01*
G02Y1465236I-2274J-1264D01*
G01X964249Y1465190D01*
Y1462905D01*
X964288Y1462852D01*
G02Y1459748I-2088J-1552D01*
G01X964249Y1459695D01*
Y1458405D01*
X964288Y1458352D01*
G02Y1455248I-2088J-1552D01*
G01X964249Y1455195D01*
Y1453405D01*
X964288Y1453352D01*
G02Y1450248I-2088J-1552D01*
G01X964249Y1450195D01*
Y1448905D01*
X964288Y1448852D01*
G02Y1445748I-2088J-1552D01*
G01X964249Y1445695D01*
Y1442928D01*
X964310Y1442869D01*
G02Y1439131I-1810J-1869D01*
G01X964249Y1439072D01*
Y1438428D01*
X964310Y1438369D01*
G02Y1434631I-1810J-1869D01*
G01X964249Y1434572D01*
Y134239D01*
G37*
G54D26*
X886417Y1963268D03*
X158071D03*
X78150Y1800512D03*
Y1650906D03*
Y1395000D03*
Y1245394D03*
Y989488D03*
Y839882D03*
Y583976D03*
Y434370D03*
Y178464D03*
Y28858D03*
G54D27*
X9843Y1859468D03*
Y1746869D03*
Y1701963D03*
Y1337396D03*
Y875216D03*
Y762617D03*
Y717711D03*
Y353144D03*
G54D25*
X1019291Y1694212D03*
Y1416024D03*
%LPC*%
G75*
G36*
G01X145810Y170800D02*
X119249Y197361D01*
Y389239D01*
X124285Y394275D01*
X124426Y394157D01*
G03X128092Y397823I1673J1993D01*
G01X127974Y397964D01*
X155249Y425239D01*
Y426045D01*
X155290Y426099D01*
G03Y428889I-1831J1395D01*
G01X155249Y428943D01*
Y443552D01*
X155341Y443611D01*
G03Y447489I-1240J1939D01*
G01X155249Y447548D01*
Y474162D01*
X155353Y474219D01*
G03Y478781I-1253J2281D01*
G01X155249Y478838D01*
Y500622D01*
X155310Y500681D01*
G03Y504419I-1811J1869D01*
G01X155249Y504478D01*
Y526899D01*
X155353Y526956D01*
G03Y531516I-1254J2280D01*
G01X155249Y531573D01*
Y592465D01*
G02X155833Y592820I400J0D01*
G03Y601432I2238J4306D01*
G02X155249Y601787I-184J355D01*
G01Y602239D01*
X162249Y609239D01*
Y637166D01*
G03Y641034I-1249J1934D01*
G01Y646361D01*
X123249Y685361D01*
Y775739D01*
X156249Y808739D01*
Y836260D01*
X156317Y836320D01*
G03X154045Y840225I-1518J1730D01*
G01X153926Y840184D01*
X152249Y841861D01*
Y922739D01*
X156249Y926739D01*
Y966501D01*
X156313Y966560D01*
G03Y969938I-1564J1689D01*
G01X156249Y969997D01*
Y977401D01*
X156313Y977460D01*
G03Y980838I-1564J1689D01*
G01X156249Y980897D01*
Y997582D01*
G02X156757Y997967I400J0D01*
G03Y1007309I1314J4671D01*
G02X156249Y1007694I-108J385D01*
G01Y1074861D01*
X113556Y1117554D01*
X113571Y1117655D01*
G03X110604Y1120622I-2572J395D01*
G01X110503Y1120607D01*
X109249Y1121861D01*
Y1194065D01*
X109253Y1194085D01*
G03Y1195015I-2254J465D01*
G01X109249Y1195035D01*
Y1228239D01*
X155749Y1274739D01*
Y1403262D01*
G02X156295Y1403634I400J0D01*
G03Y1412666I1776J4516D01*
G02X155749Y1413038I-146J372D01*
G01Y1424861D01*
X102345Y1478265D01*
X102433Y1478401D01*
G03X101373Y1481780I-1934J1249D01*
G01X101249Y1481831D01*
Y1534187D01*
X101397Y1534227D01*
G03X101968Y1538434I-597J2223D01*
G02X101896Y1538706I102J172D01*
G03X101325Y1541657I-1997J1144D01*
G01X101249Y1541717D01*
Y1544716D01*
G03Y1548584I-1249J1934D01*
G01Y1586739D01*
X155749Y1641239D01*
Y1784361D01*
X114810Y1825300D01*
X84310D01*
X75249Y1834361D01*
Y1941239D01*
X82810Y1948800D01*
X192188D01*
X266688Y1874300D01*
X323188D01*
X331749Y1865739D01*
Y1594361D01*
X323188Y1585800D01*
X277188D01*
X256749Y1565361D01*
Y1502739D01*
X266688Y1492800D01*
X320688D01*
X329249Y1484239D01*
Y1212861D01*
X314688Y1198300D01*
X269188D01*
X256249Y1185361D01*
Y1136739D01*
X262688Y1130300D01*
X318688D01*
X333249Y1115739D01*
Y789861D01*
X324188Y780800D01*
X284188D01*
X264249Y760861D01*
Y701739D01*
X269688Y696300D01*
X314688D01*
X333249Y677739D01*
Y485646D01*
X333081Y485618D01*
G03Y480482I418J-2568D01*
G01X333249Y480454D01*
Y385361D01*
X314688Y366800D01*
X290188D01*
X276188Y352800D01*
X261188D01*
X255749Y347361D01*
Y292739D01*
X264688Y283800D01*
X303688D01*
X318249Y269239D01*
Y196861D01*
X316861Y195473D01*
X316810Y195459D01*
G03X314990Y193639I689J-2509D01*
G01X314976Y193588D01*
X292188Y170800D01*
X154288D01*
X154284D01*
G03X154116I-84J-2300D01*
G01X154112D01*
X145810D01*
G37*
G36*
G01X208017Y169300D02*
X292810D01*
X319749Y196239D01*
Y269861D01*
X304310Y285300D01*
X265310D01*
X257249Y293361D01*
Y346739D01*
X261810Y351300D01*
X276810D01*
X290810Y365300D01*
X315310D01*
X334749Y384739D01*
Y480765D01*
X334845Y480823D01*
G03Y485277I-1346J2227D01*
G01X334749Y485335D01*
Y678361D01*
X334602Y678508D01*
X334601Y678589D01*
G03X332038Y681152I-2602J-39D01*
G01X331957Y681153D01*
X315310Y697800D01*
X270310D01*
X265749Y702361D01*
Y760239D01*
X284810Y779300D01*
X324810D01*
X334749Y789239D01*
Y981436D01*
X334817Y981496D01*
G03Y985404I-1718J1954D01*
G01X334749Y985464D01*
Y1116361D01*
X319310Y1131800D01*
X263310D01*
X257749Y1137361D01*
Y1184739D01*
X269810Y1196800D01*
X315310D01*
X330749Y1212239D01*
Y1484861D01*
X321310Y1494300D01*
X267310D01*
X258249Y1503361D01*
Y1564739D01*
X277810Y1584300D01*
X323810D01*
X333249Y1593739D01*
Y1866361D01*
X323810Y1875800D01*
X267310D01*
X238749Y1904361D01*
Y1937239D01*
X243810Y1942300D01*
X277188D01*
X289688Y1929800D01*
X520688D01*
X549749Y1900739D01*
Y1603068D01*
X549731Y1603028D01*
G03Y1600872I2368J-1078D01*
G01X549749Y1600832D01*
Y1577527D01*
X549738Y1577495D01*
G03Y1575805I2461J-845D01*
G01X549749Y1575773D01*
Y712646D01*
X549581Y712618D01*
G03Y707482I418J-2568D01*
G01X549749Y707454D01*
Y97361D01*
X539688Y87300D01*
X525623D01*
X525568Y87347D01*
G03X522230I-1669J-1997D01*
G01X522175Y87300D01*
X387688D01*
X337688Y37300D01*
X287673D01*
X287635Y37316D01*
G03X285571I-1032J-2388D01*
G01X285533Y37300D01*
X140310D01*
X125749Y51861D01*
Y138742D01*
X125774Y138787D01*
G03Y141313I-2275J1263D01*
G01X125749Y141358D01*
Y147742D01*
X125774Y147787D01*
G03X126071Y149445I-2275J1263D01*
G01X126055Y149545D01*
X145810Y169300D01*
X205781D01*
X205821Y169282D01*
G03X207977I1078J2368D01*
G01X208017Y169300D01*
G37*
G36*
G01X762249Y1097835D02*
Y1908239D01*
X769008Y1914998D01*
X769064Y1915010D01*
G03X771039Y1916985I-565J2540D01*
G01X771051Y1917041D01*
X775315Y1921305D01*
X775337Y1921318D01*
G03X776231Y1922212I-1338J2232D01*
G01X776244Y1922234D01*
X778810Y1924800D01*
X870102D01*
X870161Y1924710D01*
G03X874011I1925J1262D01*
G01X874070Y1924800D01*
X946688D01*
X962749Y1908739D01*
Y1742098D01*
G03Y1741902I2600J-98D01*
G01Y1411713D01*
X962681Y1411653D01*
G03Y1407747I1719J-1953D01*
G01X962749Y1407687D01*
Y1325468D01*
X962731Y1325428D01*
G03Y1323272I2368J-1078D01*
G01X962749Y1323232D01*
Y134861D01*
X906688Y78800D01*
X781310D01*
X762249Y97861D01*
Y179787D01*
X762331Y179847D01*
G03Y184053I-1532J2103D01*
G01X762249Y184113D01*
Y343277D01*
X762315Y343337D01*
G03Y346763I-1537J1713D01*
G01X762249Y346823D01*
Y1093265D01*
X762345Y1093323D01*
G03Y1097777I-1346J2227D01*
G01X762249Y1097835D01*
G37*
%LPD*%
G75*
G54D26*
X158071Y191614D03*
Y341220D03*
Y746732D03*
Y1152244D03*
Y1557756D03*
Y1813662D03*
X886417D03*
Y1557756D03*
Y1408150D03*
Y1152244D03*
Y1002638D03*
Y746732D03*
Y597126D03*
Y341220D03*
Y191614D03*
G54D16*
X68898Y17047D03*
Y190275D03*
Y422559D03*
Y595787D03*
Y828071D03*
Y1001299D03*
Y1233583D03*
Y1406811D03*
Y1639095D03*
Y1812323D03*
X167323Y179803D03*
Y353031D03*
Y585315D03*
Y758543D03*
Y990827D03*
Y1164055D03*
Y1396339D03*
Y1569567D03*
Y1801851D03*
Y1975079D03*
X895669Y179803D03*
Y353031D03*
Y585315D03*
Y758543D03*
Y990827D03*
Y1164055D03*
Y1396339D03*
Y1569567D03*
Y1801851D03*
Y1975079D03*
G54D14*
X14999Y1936050D03*
Y1940050D03*
X8499Y1937550D03*
X15099Y1944050D03*
X5303Y1947050D03*
X11703Y1951946D03*
X17499Y1961050D03*
X29699Y388484D03*
X29599Y382884D03*
X23399Y373931D03*
Y389679D03*
X23499Y381831D03*
X26299Y383854D03*
Y387629D03*
X28100Y374000D03*
X26299Y399601D03*
Y403376D03*
X29999Y398684D03*
X29899Y404384D03*
X23799Y405684D03*
X23499Y397579D03*
X35900Y412600D03*
X26524Y426720D03*
X26399Y423322D03*
X28672Y429356D03*
X29365Y421169D03*
X23399Y429051D03*
X28900Y417800D03*
X26492Y439350D03*
X26599Y442749D03*
X26899Y454850D03*
X28700Y451900D03*
X28800Y436700D03*
X28700Y445700D03*
X23399Y444799D03*
X23499Y452699D03*
Y436951D03*
X26799Y458497D03*
X26486Y462648D03*
X26499Y466250D03*
X29500Y460800D03*
X23499Y468447D03*
X23399Y476295D03*
Y460547D03*
X26299Y478404D03*
X26515Y481798D03*
X23399Y492043D03*
X23499Y484195D03*
X36499Y517775D03*
X26399Y501966D03*
Y505741D03*
X28600Y508500D03*
X38400Y514955D03*
X28664Y499429D03*
X23499Y515691D03*
Y499943D03*
X23399Y507791D03*
X36499Y521550D03*
X35338Y524746D03*
X26691Y532701D03*
X22800Y539600D03*
X23399Y523539D03*
X23499Y531439D03*
X26599Y525648D03*
Y529302D03*
X27199Y539600D03*
X39217Y554750D03*
X33307Y557938D03*
X26199Y547176D03*
X29999Y557150D03*
X33699Y561850D03*
X36499Y566350D03*
X22699Y577950D03*
X22999Y565550D03*
X28000Y578500D03*
X25581Y567763D03*
X27699Y573750D03*
X22978Y588571D03*
X28808Y593150D03*
X28700Y596549D03*
X27499Y620203D03*
Y623857D03*
X26869Y616861D03*
X23499Y618053D03*
X23999Y609250D03*
X34976Y619250D03*
X26800Y611500D03*
X32200Y603710D03*
X31598Y607102D03*
X39600Y626984D03*
X38300Y633800D03*
X30712Y624971D03*
X29999Y640550D03*
X29819Y634951D03*
X23399Y641649D03*
X23799Y625950D03*
X23499Y633801D03*
X26568Y635950D03*
Y639604D03*
X30999Y656250D03*
Y650550D03*
X23499Y665297D03*
Y649549D03*
X23725Y657471D03*
X26737Y651957D03*
X26999Y656550D03*
X23699Y673150D03*
X23499Y681045D03*
X27687Y667447D03*
Y671101D03*
X27700Y682700D03*
X29999Y694550D03*
X25999Y694870D03*
X23999Y689050D03*
X27299Y783550D03*
X35300Y789375D03*
X32800Y803050D03*
X37416Y799033D03*
X37099Y811350D03*
X26299Y815050D03*
X35559Y795112D03*
X31699Y814350D03*
X37216Y807951D03*
X39649Y822000D03*
X29299Y836901D03*
X40400Y840792D03*
X22500Y853700D03*
X29600Y854000D03*
X23299Y863050D03*
X26662Y861550D03*
X25000Y858100D03*
X20400Y1048300D03*
X20999Y1320550D03*
X23700Y1354600D03*
X20999Y1352050D03*
X25000Y1357742D03*
X22851Y1374169D03*
X22999Y1366050D03*
X23499Y1381550D03*
X25507Y1372045D03*
X25558Y1368447D03*
X32550Y1392777D03*
X27499Y1387550D03*
X24499Y1389663D03*
X28499Y1391050D03*
X32333Y1389383D03*
X30500Y1395500D03*
X33321Y1414755D03*
X29786Y1414858D03*
X23499Y1421550D03*
X23999Y1413550D03*
X32451Y1411468D03*
X28999Y1411550D03*
X32094Y1448448D03*
X28697Y1448296D03*
X36198Y1446749D03*
X27099Y1444350D03*
X30999Y1438050D03*
X27999Y1430050D03*
X23499Y1445050D03*
X22999Y1437050D03*
X23999Y1429050D03*
X33206Y1432352D03*
X30499Y1434550D03*
X30378Y1462518D03*
X33915Y1462681D03*
X29069Y1459379D03*
X36791Y1460866D03*
X23028Y1468579D03*
X23499Y1460550D03*
X22999Y1453050D03*
X34465Y1481683D03*
X30999Y1482050D03*
X32520Y1485092D03*
X28999Y1478050D03*
X23599Y1476350D03*
X23277Y1484050D03*
X34099Y1497550D03*
X30499D03*
X27499Y1495050D03*
X36999Y1494550D03*
X22999Y1500050D03*
X23799Y1508050D03*
X24499Y1492050D03*
X30115Y1511900D03*
X33512Y1512051D03*
X29631Y1533063D03*
X31999Y1517846D03*
Y1521500D03*
X35245Y1522512D03*
X35999Y1514550D03*
X29765Y1515282D03*
X24423Y1527123D03*
X22999Y1515550D03*
X37999Y1530900D03*
X24199Y1523700D03*
X25247Y1546912D03*
X38500Y1534600D03*
X32099Y1535550D03*
X26705Y1534795D03*
X30199Y1545450D03*
X36340Y1558809D03*
X34896Y1555730D03*
X38208Y1569841D03*
X25521Y1563350D03*
X30520Y1572049D03*
X24999Y1569550D03*
X31149Y1568300D03*
X23608Y1572653D03*
X24323Y1559950D03*
X27123Y1572205D03*
X39000Y1573500D03*
X22699Y1594224D03*
X31099Y1595350D03*
X28899Y1613524D03*
X32299D03*
X26999Y1610550D03*
X34884Y1615734D03*
X23499Y1618050D03*
Y1610050D03*
Y1602050D03*
X33599Y1600200D03*
X29499Y1630050D03*
X32199Y1633124D03*
X34816Y1630953D03*
X22999Y1626050D03*
X23499Y1634050D03*
X32663Y1628181D03*
X31999Y1661127D03*
X28600Y1661039D03*
X29626Y1645002D03*
X33026Y1645051D03*
X27499Y1657050D03*
X32989Y1648451D03*
X26785Y1642089D03*
X23499Y1657050D03*
X23999Y1649550D03*
X23415Y1641634D03*
X34699Y1663300D03*
X22999Y1665550D03*
X24244Y1681868D03*
X22864Y1673550D03*
X32700Y1673300D03*
X32494Y1669706D03*
X29100Y1669500D03*
X30500Y1697500D03*
X39900Y1751200D03*
X41200Y1747050D03*
X30274Y1787238D03*
X35675Y1783450D03*
X39324Y1780623D03*
X38094Y1785840D03*
X38878Y1799571D03*
X34599Y1805123D03*
X37699Y1789850D03*
X37574Y1794050D03*
X31811Y1790271D03*
X40478Y1795820D03*
X32099Y1797150D03*
X28550Y1828153D03*
X29899Y1821050D03*
X34099Y1822850D03*
X35876Y1812350D03*
X34129Y1815267D03*
X36532Y1825352D03*
X36399Y1828750D03*
X26099Y1824950D03*
X29599Y1844350D03*
X22099Y1836609D03*
X28123Y1831527D03*
X25999Y1842550D03*
X39699Y1833850D03*
X28799Y1919060D03*
X23030Y1922038D03*
X26765Y1921945D03*
X34799Y1946750D03*
X38703Y1946754D03*
X25499Y1956050D03*
X32999Y1960555D03*
X31799Y1979050D03*
X41999Y200050D03*
X61400Y452600D03*
X62497Y474346D03*
X60003Y534150D03*
X59999Y537550D03*
X42867Y548450D03*
X43099Y555850D03*
X46299Y552950D03*
X49799Y559150D03*
X42599Y567850D03*
X47543Y578340D03*
X44959Y575756D03*
X60076Y595777D03*
X55499Y595650D03*
X42202Y608195D03*
X41400Y611500D03*
X47626Y611300D03*
X45701Y607700D03*
X42709Y625607D03*
X41500Y642800D03*
X57800Y634300D03*
X44900Y642800D03*
X47101Y632355D03*
X41500Y635000D03*
X52500D03*
X48999Y642900D03*
X50410Y695801D03*
X50300Y699200D03*
X45100Y793100D03*
X44046Y799554D03*
X46887Y803413D03*
X51100Y806300D03*
X49900Y813200D03*
X56281Y801350D03*
X50399Y836250D03*
X46700Y820100D03*
X54074Y815750D03*
X62405Y820300D03*
X46576Y832951D03*
X48346Y844529D03*
X58699Y837250D03*
X44697Y1546793D03*
X44299Y1550950D03*
X42199Y1601050D03*
X47400Y1721700D03*
X42000Y1740100D03*
X47717Y1731337D03*
X47800Y1740500D03*
X45877Y1728477D03*
Y1724823D03*
X47000Y1737100D03*
X43600D03*
X42275Y1754000D03*
X45799Y1757650D03*
X47440Y1761391D03*
X47400Y1765250D03*
X43751Y1780559D03*
X46999Y1779550D03*
X46199Y1783050D03*
X43925Y1767890D03*
X47604Y1769005D03*
X45782Y1771877D03*
X47499Y1775350D03*
X47899Y1798650D03*
X48049Y1791450D03*
X42199Y1792250D03*
X46799Y1794900D03*
X61009Y1822340D03*
X60449Y1842550D03*
X46499Y1836550D03*
X47166Y1839884D03*
X43099Y1833850D03*
X57999Y1891050D03*
X42499Y1902550D03*
X48499Y1897050D03*
X44368Y1951450D03*
X44399Y1942250D03*
X42532Y1946783D03*
X53999Y1946650D03*
X50299D03*
X46565Y1946703D03*
X45999Y1971450D03*
X50499Y1961550D03*
X43462Y1961160D03*
X78700Y74200D03*
Y70700D03*
X74999Y70550D03*
Y74050D03*
X74499Y80650D03*
Y84050D03*
X65999Y216050D03*
X65000Y455500D03*
X62503Y470946D03*
X66199Y475184D03*
Y469884D03*
X77499Y469550D03*
X62978Y486217D03*
X63067Y489616D03*
X66299Y490784D03*
Y485484D03*
X77999Y493050D03*
X77499Y502550D03*
X65599Y514250D03*
X63499Y538550D03*
Y533050D03*
X68000Y546500D03*
X72500Y545000D03*
X81251Y607249D03*
Y619251D03*
X82499Y627050D03*
X80499Y664550D03*
X74499Y662050D03*
X78499Y654050D03*
X76999Y664550D03*
X81999Y668050D03*
X65500Y817700D03*
X80500Y817000D03*
X76540Y850938D03*
X75500Y847700D03*
X68860Y838706D03*
X69499Y842950D03*
X63499Y843050D03*
X74220Y854150D03*
X72362Y849550D03*
X72000Y1013400D03*
X63273Y1023974D03*
X66499Y1025050D03*
X75500Y1012261D03*
X65486Y1031515D03*
X80000Y1090500D03*
X74500Y1097550D03*
X79899Y1104550D03*
X74399Y1111550D03*
X76999Y1196550D03*
X78499Y1273550D03*
X78613Y1282664D03*
X78779Y1302664D03*
Y1312664D03*
X77758Y1357742D03*
X76000Y1431100D03*
X80043Y1544691D03*
X78600Y1561900D03*
X75000Y1561800D03*
X74400Y1574800D03*
X80400Y1571766D03*
X82329Y1568117D03*
X79000Y1555500D03*
X82429D03*
X74800Y1584700D03*
X78100Y1688189D03*
X74500Y1692000D03*
X74400Y1778100D03*
X80099Y1817250D03*
X93999Y58550D03*
X92900Y66128D03*
X92999Y86128D03*
X97499Y90050D03*
X92999Y96128D03*
X89603Y132629D03*
X86899Y130567D03*
X86599Y126750D03*
X95350Y204550D03*
X89800Y208550D03*
X96900Y510000D03*
X93200Y510500D03*
X95500Y513400D03*
X98900D03*
X83700Y529500D03*
X88999Y538050D03*
X104502Y530552D03*
X86199Y536025D03*
Y532250D03*
X89000Y816500D03*
X90000Y826000D03*
X90500Y831500D03*
X98700Y822550D03*
X98000Y833500D03*
X98700Y842600D03*
X92999Y868550D03*
X92499Y876550D03*
X94999Y901550D03*
X89469Y935588D03*
X85999Y940429D03*
X86399Y937050D03*
X89499Y942850D03*
X102100Y968500D03*
X99000Y965000D03*
X104600Y980500D03*
X90000Y993100D03*
X92600Y996100D03*
X88000Y1008500D03*
X101541Y1262607D03*
X101399Y1292550D03*
X102700Y1321363D03*
X102000Y1341000D03*
X91279Y1340642D03*
X86165Y1339050D03*
X86890Y1342860D03*
X101500Y1352000D03*
X89999Y1348050D03*
X86890Y1346635D03*
X102350Y1344500D03*
Y1348154D03*
X97229Y1373337D03*
X97000Y1377600D03*
X100499Y1479650D03*
X83932Y1544705D03*
X100800Y1536450D03*
X96200Y1550100D03*
X99899Y1539850D03*
X100000Y1546650D03*
X90324Y1538800D03*
X97499Y1554550D03*
X98144Y1534309D03*
X96999Y1558050D03*
X89373Y1561073D03*
X85600Y1561500D03*
X95499Y1665418D03*
X92900Y1678176D03*
X93999Y1703050D03*
X92873Y1708176D03*
X92479Y1718176D03*
X89306Y1746856D03*
X89499Y1753575D03*
X85341Y1752245D03*
X85194Y1748848D03*
X99199Y1761899D03*
X99999Y1753575D03*
X101399Y1784700D03*
X85599Y1797350D03*
X96600Y1826000D03*
X86649Y1817100D03*
X90000Y1827900D03*
X93500D03*
X97999Y1843050D03*
X112999Y124050D03*
X111790Y132259D03*
X115876Y125973D03*
Y130050D03*
X114900Y177900D03*
X122397Y252688D03*
X122799Y249150D03*
X124999Y246050D03*
X123378Y255944D03*
X107499Y497050D03*
X107526Y528996D03*
X109400Y543200D03*
X106000D03*
X105100Y600000D03*
X107000Y604800D03*
X125499Y635550D03*
Y638950D03*
X124999Y643050D03*
X110500Y790200D03*
X111100Y813400D03*
X111200Y799450D03*
X111207Y810001D03*
X110700Y795700D03*
X111089Y806603D03*
X110800Y803100D03*
X110499Y834550D03*
X106749Y934367D03*
X108441Y924705D03*
X108845Y931657D03*
X109099Y928250D03*
X107300Y986000D03*
X107400Y992900D03*
X124100Y1047100D03*
X123999Y1054050D03*
Y1050650D03*
X120100Y1053200D03*
X116700Y1063500D03*
X112699Y1058974D03*
X105499Y1080550D03*
X106718Y1076050D03*
X121500Y1083600D03*
X121100Y1075300D03*
X117499Y1079300D03*
X105600Y1069500D03*
X124423Y1077523D03*
Y1081177D03*
X120749Y1093990D03*
X116249Y1102550D03*
X112999Y1103740D03*
X123999Y1102550D03*
X108999Y1102050D03*
X106162Y1205702D03*
X114999Y1210363D03*
X118999Y1219050D03*
X123970Y1221573D03*
X116999Y1288050D03*
X120507Y1317050D03*
X111499Y1311800D03*
X107999Y1307713D03*
X113000Y1341000D03*
X107228Y1330552D03*
X107500Y1340500D03*
X109228Y1337090D03*
Y1333315D03*
X119499Y1339050D03*
X113500Y1352000D03*
X110499Y1365050D03*
X109999Y1355050D03*
X112440Y1358196D03*
X112999Y1361550D03*
X121000Y1364000D03*
X113500Y1344500D03*
Y1348154D03*
X125100Y1366000D03*
X117390Y1426201D03*
X119507Y1423540D03*
X117390Y1429976D03*
X104935Y1440634D03*
X104999Y1444941D03*
X107328Y1438218D03*
X114499Y1432050D03*
X107999Y1448050D03*
X124290Y1469241D03*
X123808Y1465050D03*
X105099Y1459150D03*
X123999Y1473050D03*
X122199Y1476050D03*
X118499Y1694050D03*
X109499Y1712213D03*
X104999Y1708963D03*
X117249Y1712090D03*
X112753Y1716613D03*
X122642Y1704243D03*
X112562Y1720613D03*
X123749Y1711550D03*
X109499Y1743550D03*
X107499Y1736550D03*
X109399Y1739550D03*
X106999Y1746290D03*
X110099Y1759875D03*
X123393Y1870859D03*
X123592Y1874254D03*
X127999Y157050D03*
X147099Y245350D03*
X141499Y427550D03*
Y423050D03*
X135499Y517550D03*
X138999Y524213D03*
X137899Y545451D03*
X138416Y553500D03*
X141300Y565900D03*
X127999Y645550D03*
X131400Y644600D03*
X144238Y645356D03*
X128725Y636626D03*
X128479Y640589D03*
X141773Y643013D03*
X144238Y649131D03*
X140499Y649350D03*
X134300Y646400D03*
X141500Y711000D03*
X137100Y1084800D03*
X140800Y1076300D03*
X137481Y1077557D03*
X137477Y1081177D03*
X138600Y1124600D03*
X130699Y1210653D03*
X125999Y1315550D03*
X132999Y1319550D03*
X142667Y1319218D03*
X143700Y1332500D03*
X133475Y1331200D03*
X140000Y1332600D03*
X138000Y1359025D03*
X129000Y1356500D03*
X142999Y1456373D03*
X139815Y1454438D03*
X139235Y1460973D03*
X127898Y1462441D03*
X142900Y1460000D03*
X131999Y1710050D03*
X141500Y1715500D03*
X135499Y1710150D03*
X141999Y1764550D03*
X137999Y1861497D03*
Y1865151D03*
X141101Y1866545D03*
X140999Y1859550D03*
X135999Y1881550D03*
X152499Y149550D03*
X154200Y168500D03*
X149400Y166400D03*
X149999Y243504D03*
Y239729D03*
X157440Y283924D03*
Y303924D03*
Y313924D03*
X165699Y428050D03*
X153459Y427494D03*
X154101Y445550D03*
X159600Y446399D03*
X163549Y517100D03*
X163449Y521650D03*
X149000Y537500D03*
X150500Y545000D03*
X160932Y549468D03*
X150750Y540416D03*
X157000Y573851D03*
X160824Y577000D03*
X161000Y639100D03*
X158885Y679436D03*
Y689436D03*
X158385Y719436D03*
X159500Y814700D03*
X165499Y815550D03*
X153500Y834600D03*
X154799Y838050D03*
X153499Y918550D03*
X163500Y937100D03*
X160399Y922850D03*
X152500Y960000D03*
X154749Y979149D03*
Y968249D03*
X164700Y1085400D03*
X159000Y1083000D03*
X157700Y1114948D03*
X157600Y1124948D03*
X149562Y1315987D03*
X147400Y1321600D03*
X148024Y1333525D03*
X150338Y1453958D03*
X152499Y1462940D03*
X157440Y1490460D03*
Y1500460D03*
Y1520460D03*
Y1530460D03*
X157400Y1596550D03*
X160200Y1598500D03*
X165575Y1676975D03*
X152633Y1677967D03*
X150999Y1713550D03*
X165900Y1790500D03*
X161900Y1793400D03*
X159421Y1925972D03*
X175999Y82428D03*
X174999Y79050D03*
X175499Y86572D03*
X176399Y94872D03*
X178999Y79050D03*
X186999Y99050D03*
X169999Y129050D03*
X188999Y120800D03*
X173499Y149050D03*
X187699Y492850D03*
X173100Y483100D03*
X172499Y491053D03*
X176799Y493850D03*
X188000Y484500D03*
X171722Y513827D03*
X182499Y532550D03*
X168453Y527949D03*
X183499Y556100D03*
X172660Y815731D03*
X169106Y815865D03*
X174199Y841050D03*
X172500Y919294D03*
X172000Y931600D03*
X171100Y935000D03*
X171000Y939500D03*
X172000Y961000D03*
X170250Y948500D03*
X179499Y1275550D03*
X181000Y1365500D03*
X180500Y1369900D03*
X179999Y1655887D03*
X171999Y1662250D03*
X169600Y1682300D03*
X169100Y1685800D03*
X174250Y1694500D03*
X177900Y1690400D03*
X205938Y72528D03*
X201499Y104550D03*
X205499Y105550D03*
X207999Y109550D03*
X197899Y165075D03*
X199900Y554050D03*
X193549Y575875D03*
X200000Y818000D03*
X200539Y890300D03*
X200799Y896600D03*
X198924Y975975D03*
X199149Y1362900D03*
X194700Y1385700D03*
X193500Y1647000D03*
X201499Y1781050D03*
X194049Y1792600D03*
X210605Y70692D03*
X210685Y74725D03*
X215138Y72559D03*
X210634Y66863D03*
X210638Y62959D03*
X225499Y68550D03*
X210738Y82159D03*
Y78459D03*
X230749Y76300D03*
X213499Y104650D03*
X223499Y108150D03*
X218499Y190550D03*
X225298Y281114D03*
X213499Y283864D03*
X214063Y318114D03*
X213400Y355300D03*
X224998Y357049D03*
X220000Y516400D03*
X216999Y686550D03*
X213999Y725050D03*
X230849Y726050D03*
X228999Y765550D03*
X218224Y765325D03*
X211750Y894600D03*
X229562Y904113D03*
X215499Y905550D03*
X221800Y1069300D03*
X221300Y1083238D03*
X229800Y1073600D03*
X226800Y1093400D03*
X224750Y1483950D03*
X229025Y1471576D03*
X227814Y1887513D03*
X223436Y1890465D03*
X229800Y1875700D03*
X218100Y1886400D03*
X214999Y1909550D03*
X213562Y1926113D03*
X220062Y1931113D03*
X213138Y1952703D03*
X210999Y1942050D03*
X246999Y51550D03*
X246499Y42550D03*
X246999Y69550D03*
Y60550D03*
X246499Y86050D03*
Y80550D03*
X245499Y100550D03*
X233749Y110800D03*
X237899Y107050D03*
X247800Y269700D03*
X250300Y275100D03*
X250400Y283100D03*
X239600Y278600D03*
X231800Y318414D03*
X233998Y357549D03*
X239400Y357400D03*
X246800Y677100D03*
X249700Y682500D03*
X238500Y680800D03*
X249800Y689900D03*
X252499Y726050D03*
X241600Y765700D03*
X236800Y765800D03*
X233500Y1066100D03*
X242000Y1066000D03*
X247500Y1085500D03*
X251500Y1136700D03*
X241000Y1469600D03*
X233700Y1481600D03*
X232650Y1493450D03*
X231800Y1887100D03*
X232314Y1890513D03*
X236225Y1883125D03*
X231999Y1914050D03*
X249499Y1928050D03*
X240964Y1934113D03*
X253999Y44050D03*
X253871Y291410D03*
X252935Y319114D03*
X254499Y697700D03*
X255000Y1125700D03*
X256000Y1133000D03*
X261999Y1516050D03*
X257499Y1911050D03*
X264499Y1964050D03*
X291999Y94050D03*
X282800Y87500D03*
X293999Y293550D03*
X284999Y338650D03*
X281499Y338550D03*
X294500Y339000D03*
X279939Y728610D03*
X285499Y745050D03*
X282099D03*
X292999Y743650D03*
X277039Y740300D03*
X295000Y1513000D03*
X289999Y1554650D03*
X293700Y1553351D03*
X276039Y1551300D03*
X283499Y1556050D03*
X279999D03*
X291400Y1561500D03*
X285499Y1930050D03*
X288709Y1948042D03*
X284999Y1947691D03*
X280689Y1942710D03*
X296099Y17100D03*
X305099Y17000D03*
X311400Y17100D03*
X308999Y87050D03*
X297499Y97550D03*
X315800Y100500D03*
X298800Y333000D03*
X301249Y346050D03*
X313039Y352350D03*
X308999Y716450D03*
X315999Y718950D03*
X298000Y743500D03*
X310999Y757050D03*
X314999Y1527550D03*
X297800Y1561600D03*
X312999Y1566050D03*
X310249Y1569800D03*
X313499Y1919050D03*
X310499Y1957050D03*
X315999Y1958550D03*
X317000Y17300D03*
X324800Y89400D03*
X323400Y105200D03*
X326499Y334054D03*
Y337454D03*
X321900Y364600D03*
X327999Y740550D03*
X323249Y749010D03*
X327749Y744050D03*
X324959Y766750D03*
X329499Y801550D03*
X330540Y795509D03*
X320499Y798050D03*
X326500Y1550200D03*
X324000Y1562500D03*
X330300Y1561200D03*
X323999Y1577250D03*
X325221Y1927272D03*
X331622Y1944767D03*
X329999Y1952273D03*
X332103Y1948133D03*
X327100Y1966472D03*
X343499Y31650D03*
X354999Y72050D03*
X343499Y60150D03*
X341499Y63050D03*
Y67110D03*
X357503Y77043D03*
X344520Y406329D03*
X350499Y715050D03*
X340699Y1046086D03*
X345499Y1096550D03*
X345424Y1310050D03*
X347324Y1524000D03*
X354500Y1559500D03*
X349774Y1582900D03*
X354000Y1584900D03*
X353499Y1710450D03*
X348499Y1762050D03*
X358999Y61550D03*
X374499Y77550D03*
X365499Y86550D03*
X371999Y549300D03*
X375999Y698550D03*
X371500Y880600D03*
X364499Y1099050D03*
X372999Y1123550D03*
X370149Y1320050D03*
X366149Y1554050D03*
X377900Y1703800D03*
X398799Y36152D03*
X381999Y50150D03*
X382339Y41610D03*
X381999Y53550D03*
X394199Y45050D03*
X381999Y57050D03*
X385999Y78050D03*
X400499Y406329D03*
X394649Y630600D03*
X390999Y1514398D03*
Y1517798D03*
X385499Y1735050D03*
X401499Y80550D03*
X402499Y1476850D03*
X400999Y1575550D03*
X659549Y1810634D03*
X690249Y1805634D03*
X711652Y1822109D03*
X711848Y1825504D03*
X752999Y746842D03*
X757499Y745342D03*
X755600Y1149800D03*
X758499Y1371050D03*
X758199Y1553650D03*
X755000Y1825000D03*
X759114Y1957673D03*
X770999Y302050D03*
Y290050D03*
Y295550D03*
X763571Y295622D03*
X777999Y296050D03*
X772499Y323050D03*
X772873Y326924D03*
X760778Y345050D03*
X768178Y333964D03*
X780499Y330050D03*
X771105Y722789D03*
X766499Y732842D03*
X762999Y734550D03*
X769999Y733050D03*
X771999Y1124550D03*
X772499Y1130050D03*
X779499Y1131050D03*
X767083Y1134550D03*
X768199Y1138590D03*
X774542Y1530050D03*
X774577Y1533796D03*
X771225Y1539474D03*
X767936Y1540336D03*
X774500Y1788000D03*
X770999Y1820550D03*
X771499Y1936550D03*
X767999Y1945173D03*
X764908Y1946592D03*
X771499Y1940050D03*
X785499Y291050D03*
X786978Y298529D03*
X791499Y333050D03*
X789999Y336550D03*
X784499Y334050D03*
X781999Y725550D03*
X788999Y736050D03*
X791999Y733050D03*
X784939Y733550D03*
X792154Y1135926D03*
X784439Y1136550D03*
X789499Y1138050D03*
X784499Y1529050D03*
X784577Y1535628D03*
X791499Y1543550D03*
X793999Y1541050D03*
X788000Y1788000D03*
X793000Y1803500D03*
X795849Y1805500D03*
X791999Y1819050D03*
X783499Y1827050D03*
X785939Y1946800D03*
X792499Y1949050D03*
X794499Y1941050D03*
X782999Y1937050D03*
X802099Y1961950D03*
X820749Y163850D03*
X813249Y163800D03*
X821999Y193116D03*
X822100Y261700D03*
Y279500D03*
X816700Y274300D03*
X820600Y664300D03*
X813200Y675900D03*
X815400Y1078800D03*
X803199Y1151850D03*
X822100Y1466800D03*
X814700Y1486300D03*
X804899Y1556950D03*
X812000Y1799500D03*
X821249Y1791250D03*
X811000Y1793000D03*
X822499Y1815164D03*
X807000Y1822300D03*
X803500Y1822708D03*
X822700Y1871100D03*
X805900Y1887560D03*
X841499Y135550D03*
X827499Y163550D03*
X839249Y164050D03*
X829917Y216200D03*
X833576Y215432D03*
X837999Y219550D03*
X842499Y280924D03*
X827500Y274500D03*
X836500Y274950D03*
X827499Y313424D03*
X829800Y666650D03*
X835150Y677650D03*
X825700Y1083100D03*
X825800Y1072300D03*
X827700Y1487600D03*
X836625Y1487400D03*
X828500Y1877800D03*
X834799Y1946950D03*
X861999Y146550D03*
X854400Y264600D03*
X847878Y250040D03*
X851278Y249974D03*
X847450Y246666D03*
X850999Y246550D03*
X858478Y274050D03*
X865499Y288050D03*
X851172Y655432D03*
X847772Y655370D03*
X851197Y652032D03*
X847493Y651981D03*
X852696Y671197D03*
X850833Y1061441D03*
X847233Y1061492D03*
X847355Y1058094D03*
X851042Y1058047D03*
X852333Y1077716D03*
X860133Y1084142D03*
X864499Y1128750D03*
X860799Y1358925D03*
X861849Y1376050D03*
X848888Y1466402D03*
X852288Y1466346D03*
X848861Y1462463D03*
X852429Y1462948D03*
X854327Y1477550D03*
X858827Y1485696D03*
X863699Y1501250D03*
X862800Y1712700D03*
X851500Y1821400D03*
X849375Y1824982D03*
X854905Y1825583D03*
X853499Y1871036D03*
X850099Y1871056D03*
X854480Y1867578D03*
X849999Y1867550D03*
X863788Y1866953D03*
X865501Y1858747D03*
X859314Y1891365D03*
X854814Y1883550D03*
X863699Y1906450D03*
X857099Y1917650D03*
X882499Y147050D03*
X867500Y163924D03*
X867576Y159924D03*
X878078Y240103D03*
Y243878D03*
X874928Y238822D03*
X874790Y244748D03*
X871999Y283924D03*
X872136Y273924D03*
X886600Y303924D03*
X868799Y294750D03*
X867899Y321550D03*
X886200Y313924D03*
X868299Y336150D03*
X879750Y570550D03*
X879950Y565050D03*
X878596Y645573D03*
X874999Y644550D03*
X878596Y649348D03*
X875270Y650059D03*
X883083Y979183D03*
X879708Y971892D03*
X878233Y1051095D03*
X877964Y1054485D03*
X874733Y1055792D03*
X874999Y1049550D03*
X872086Y1084948D03*
X871999Y1094948D03*
X871499Y1124948D03*
X872086Y1114948D03*
X866700Y1379796D03*
X866596Y1375796D03*
X878054Y1456450D03*
X877853Y1459991D03*
X874499Y1460550D03*
X874986Y1454983D03*
X872086Y1490460D03*
X871999Y1500460D03*
Y1520460D03*
X872086Y1530460D03*
X867523Y1542821D03*
X867199Y1535150D03*
X886439Y1717600D03*
X873800Y1733600D03*
X879700Y1786300D03*
X879664Y1782213D03*
X866914Y1861840D03*
Y1865615D03*
X871921Y1905972D03*
X871421Y1895972D03*
X872086Y1925972D03*
Y1935972D03*
X901499Y92050D03*
X897555Y90494D03*
X898999Y99050D03*
X902499Y110550D03*
X898999D03*
X907499Y131800D03*
X896999Y141550D03*
X902999Y556050D03*
X900499Y962100D03*
X889800Y1711500D03*
X923761Y85550D03*
X928561Y95181D03*
X928428Y83714D03*
X928508Y87747D03*
X928561Y91481D03*
X928457Y79885D03*
X928461Y75981D03*
X916499Y115050D03*
X926999D03*
Y122050D03*
X910999Y124550D03*
X922049Y574375D03*
Y978575D03*
X921549Y1788475D03*
X917499Y1796550D03*
X932961Y85581D03*
X943499Y82550D03*
X930999Y115550D03*
X938499D03*
X946899Y122550D03*
X937999Y122050D03*
X934499Y118750D03*
X939549Y175175D03*
X961499Y93350D03*
X958999Y96050D03*
X961499Y100050D03*
X966499Y552050D03*
X965999Y954550D03*
X965150Y1639500D03*
X961702Y1636102D03*
X969600Y1638300D03*
X967600Y1651100D03*
X971558Y1646500D03*
X981200Y1618002D03*
X986400Y1639302D03*
X990425Y1633898D03*
X987029Y1634075D03*
X977500Y1660500D03*
X989502Y1646000D03*
X988800Y1658300D03*
X981500Y1653000D03*
X980800Y1659600D03*
X982050Y1649302D03*
X978000Y1668000D03*
X989000Y1663802D03*
X987200Y1675600D03*
X989900Y1678800D03*
X974000Y1670700D03*
X984211Y1667500D03*
G54D11*
X17600Y5604D03*
X10000Y16500D03*
X11999Y53550D03*
X11499Y34050D03*
X11999Y69050D03*
Y88550D03*
X11499Y106050D03*
X11999Y124550D03*
X11499Y142050D03*
X11999Y177050D03*
Y161550D03*
Y196550D03*
X11499Y214050D03*
X9499Y229050D03*
X8999Y246550D03*
X9499Y281550D03*
Y266050D03*
Y301050D03*
X15499Y328050D03*
X8999Y318550D03*
X15499Y342550D03*
Y360050D03*
X14799Y751450D03*
X8599Y751650D03*
X17299Y773950D03*
X10999Y774050D03*
X8999Y889550D03*
X8499Y907050D03*
X8999Y942050D03*
Y926550D03*
Y961550D03*
X8499Y979050D03*
X8999Y988550D03*
Y1025550D03*
X8499Y1006050D03*
X8999Y1041050D03*
Y1060550D03*
X8499Y1089050D03*
Y1078050D03*
X7999Y1106550D03*
X8499Y1126050D03*
Y1141550D03*
Y1161050D03*
X7999Y1192550D03*
Y1178550D03*
X7499Y1210050D03*
X7999Y1229550D03*
Y1245050D03*
Y1264550D03*
X7499Y1282050D03*
X8299Y1320050D03*
X8799Y1302550D03*
X18099Y1343550D03*
X9399Y1347350D03*
X15299Y1723450D03*
X15399Y1708350D03*
X7099Y1717750D03*
X7199Y1731450D03*
X14899Y1736250D03*
X15299Y1753250D03*
X6099Y1753750D03*
X11299Y1850050D03*
X9099Y1881550D03*
X8499Y1979550D03*
X11500Y1987000D03*
X36000Y5604D03*
X23499Y27050D03*
X40999Y27550D03*
X27799Y38450D03*
X40999Y42050D03*
X25799Y64050D03*
X28399Y94950D03*
X34999Y108550D03*
X41399Y134150D03*
X27999Y131050D03*
Y145550D03*
Y163050D03*
X23999Y243550D03*
Y229050D03*
Y261050D03*
X39999Y327550D03*
Y342050D03*
Y359550D03*
Y576550D03*
X36999Y725050D03*
Y719550D03*
X37499Y714050D03*
X41499Y719550D03*
X26399Y750850D03*
X36499Y740050D03*
Y732550D03*
X39899Y754850D03*
X39399Y768750D03*
X27199Y764950D03*
X28599Y775450D03*
X26799Y874550D03*
X26099Y891650D03*
X25699Y916150D03*
X25099Y942150D03*
X23899Y957950D03*
X24799Y992250D03*
X33899Y1005950D03*
X21499Y1073250D03*
X21399Y1090850D03*
X21299Y1300250D03*
X21799Y1282750D03*
X31499Y1849750D03*
X39399Y1864350D03*
X23999Y1857950D03*
X27199Y1874350D03*
X34799Y1890050D03*
X26500Y1987000D03*
X55700Y5900D03*
X50999Y21150D03*
Y47750D03*
X59499Y90550D03*
Y76050D03*
Y108050D03*
X52499Y130550D03*
Y145050D03*
Y162550D03*
X41699Y183250D03*
X48499Y243050D03*
Y228550D03*
Y260550D03*
X42999Y275650D03*
X51099Y300050D03*
X52199Y342350D03*
X42299Y564150D03*
X62055Y561550D03*
X49555Y563550D03*
X61099Y603236D03*
X52333Y641295D03*
X43499Y657550D03*
X47800Y692800D03*
X53210Y701486D03*
X50999Y720050D03*
X46499Y719550D03*
X51499Y724550D03*
X46499D03*
X41999D03*
X46499Y730550D03*
X41999Y735050D03*
Y731050D03*
X46499Y735050D03*
X41999Y739550D03*
X46499Y739050D03*
X51999Y767050D03*
X47999Y767550D03*
X52499Y771550D03*
X47999D03*
X53999Y791000D03*
X52999Y1871550D03*
X57499Y1871050D03*
X45699Y1875550D03*
X47499Y1915050D03*
Y1930550D03*
X62499Y1939550D03*
X58999Y1958050D03*
X61500Y1987500D03*
X44500Y1987000D03*
X55999Y1982550D03*
X73900Y6200D03*
X65499Y27050D03*
Y41550D03*
Y59050D03*
X77165Y110799D03*
X71015Y123666D03*
X78165Y137116D03*
X75299Y261750D03*
X76099Y414250D03*
X75300Y454100D03*
X67300Y450200D03*
X68899Y445450D03*
X66099Y500950D03*
X77165Y514650D03*
X70800Y540300D03*
X75999Y556640D03*
X72599Y578236D03*
X79299Y794150D03*
X67999Y790400D03*
X76399Y820450D03*
X70100Y818900D03*
X77499Y921550D03*
X77002Y952079D03*
X76711Y948089D03*
X77499Y962152D03*
X72799Y982950D03*
X65799Y994050D03*
X67000Y1011500D03*
X77165Y1327335D03*
X77166Y1353400D03*
X76499Y1507050D03*
Y1498050D03*
Y1512050D03*
Y1503050D03*
X76999Y1528050D03*
Y1519050D03*
X81499Y1589050D03*
X83499Y1594050D03*
X78999Y1593550D03*
X74999D03*
X74499Y1602050D03*
Y1598050D03*
X83499D03*
Y1602050D03*
X78999Y1598050D03*
Y1602050D03*
X83599Y1744750D03*
X77165Y1759550D03*
X78529Y1788113D03*
X62999Y1914550D03*
Y1926050D03*
X81499Y1915550D03*
X82499Y1957050D03*
X73499D03*
X66499D03*
X73499Y1945550D03*
X79500Y1987500D03*
X65499Y1982550D03*
X73499D03*
X82999D03*
X90900Y5800D03*
X90899Y14850D03*
X96999Y49550D03*
X92999Y52050D03*
X97800Y36000D03*
X96900Y40400D03*
X93000Y44900D03*
X92900Y39700D03*
X95814Y136065D03*
X96184Y151065D03*
Y166065D03*
X97999Y199050D03*
X92899Y231450D03*
X86899Y242750D03*
X93199Y279650D03*
X84899Y289250D03*
X90899Y309550D03*
X94199Y325550D03*
X93499Y337450D03*
X89899Y368350D03*
X95499Y355450D03*
X89999Y396450D03*
X87599Y403950D03*
X95399Y416350D03*
X89099Y426150D03*
X99399Y437450D03*
X93500Y445300D03*
X97699Y449850D03*
X93199D03*
X97999Y445550D03*
X94500Y456800D03*
X100500Y456700D03*
X98999Y488050D03*
X94499Y486550D03*
X93499Y477050D03*
X97699Y481550D03*
Y477050D03*
X93499Y481550D03*
X101500Y536500D03*
X93599Y581236D03*
X93100Y571640D03*
X92599Y606236D03*
X98001Y856950D03*
X97800Y851800D03*
X93808Y852063D03*
X94001Y856895D03*
X97499Y862050D03*
X93299D03*
X93499Y897152D03*
X93900Y882400D03*
X97900D03*
X97700Y887400D03*
X93690Y887139D03*
X97499Y892550D03*
X93499Y892050D03*
X93000Y907165D03*
X83988Y934028D03*
X86700Y982100D03*
X102999Y1188050D03*
X104999Y1231050D03*
X100999Y1231032D03*
X103499Y1305050D03*
X93316Y1351000D03*
X96000Y1369000D03*
X96100Y1384650D03*
X97300Y1564100D03*
X92499Y1589050D03*
X86999D03*
X90999Y1628550D03*
Y1624550D03*
X91121Y1632549D03*
X86299Y1632550D03*
X85999Y1628550D03*
Y1624550D03*
X84099Y1737150D03*
X93499Y1759550D03*
X94336Y1773113D03*
X104417Y1791480D03*
X97999Y1815050D03*
X104500Y1813400D03*
X83999Y1945050D03*
X92499Y1959050D03*
X101699Y1983850D03*
X98000Y1987500D03*
X91499Y1983050D03*
X107000Y6000D03*
X116400Y56000D03*
X114800Y68500D03*
X123499Y149050D03*
Y140050D03*
X117500Y162300D03*
X124300Y167800D03*
X109499Y410250D03*
X124899Y409050D03*
X126099Y396150D03*
X111299Y425850D03*
X122499Y427900D03*
X108599Y557236D03*
X108900Y587600D03*
X112200Y762200D03*
X112000Y773000D03*
X111299Y821050D03*
X112999Y901150D03*
X106500Y943000D03*
X105300Y960300D03*
X110999Y1130550D03*
X115200Y1130300D03*
X110999Y1126050D03*
Y1122050D03*
Y1118050D03*
X114999Y1126050D03*
Y1122050D03*
Y1118050D03*
X106999Y1114960D03*
X120999Y1188050D03*
X111999D03*
X121657Y1224604D03*
X120999Y1228550D03*
X120499Y1264550D03*
X123938Y1267623D03*
X117149Y1267550D03*
X123500Y1360300D03*
X122600Y1565000D03*
X124999Y1616050D03*
Y1620050D03*
Y1629050D03*
Y1633050D03*
X119999Y1629050D03*
X120100Y1633100D03*
X122499Y1668550D03*
Y1672550D03*
X118999Y1670550D03*
X117499Y1745050D03*
X123499Y1747050D03*
X120299Y1796150D03*
X111499Y1877550D03*
Y1882550D03*
X122999Y1883050D03*
X115999Y1882550D03*
X116499Y1877550D03*
X122999Y1889050D03*
X119999Y1978550D03*
X119499Y1972550D03*
X108499Y1981750D03*
X115000Y1987000D03*
X129100Y55900D03*
X127499Y65050D03*
X141999Y65550D03*
X133999Y149050D03*
X142999Y141050D03*
X132999Y141550D03*
X144499Y149050D03*
X131799Y201950D03*
X142688Y218861D03*
X143110Y203861D03*
X133000Y240500D03*
X135399Y277050D03*
X130799Y300250D03*
X130099Y326150D03*
X134699Y356050D03*
X139399Y372350D03*
X133499Y445050D03*
X128999Y445550D03*
X130000Y452000D03*
X135999Y472550D03*
X135140Y478930D03*
X139200Y484300D03*
X134499Y488050D03*
X145649Y509550D03*
X136349Y509050D03*
X140499Y499050D03*
X136299D03*
X140000Y587700D03*
X140499Y600550D03*
X143999Y605550D03*
X140499Y626050D03*
X131099Y700450D03*
X139099Y707150D03*
X141234Y1029885D03*
X140864Y1044885D03*
X137900Y1103400D03*
X139100Y1097100D03*
X134500Y1108100D03*
X143200Y1116300D03*
X133200Y1132100D03*
X126400Y1138100D03*
X145900Y1163200D03*
X144399Y1171150D03*
X141499Y1185550D03*
X128400Y1188600D03*
X143899Y1196750D03*
X142499Y1205550D03*
X130999Y1198050D03*
X144149Y1230113D03*
Y1226113D03*
Y1222113D03*
X126499Y1264550D03*
X145999Y1353050D03*
X143199Y1412050D03*
X140799Y1435460D03*
X129100Y1564700D03*
X127200Y1569800D03*
X126562Y1670613D03*
X144499Y1745550D03*
X137999Y1747723D03*
X129999Y1747050D03*
X126599Y1789650D03*
X142144Y1801644D03*
X143490Y1855972D03*
X127499Y1889050D03*
X126999Y1882550D03*
X142499Y1905972D03*
X141499Y1895972D03*
X127499Y1978550D03*
X133499D03*
X132999Y1972550D03*
X126999D03*
X146899Y1961750D03*
X146000Y1987500D03*
X128500D03*
X157299Y5150D03*
X167499Y43550D03*
X156499Y66050D03*
X152999Y141050D03*
X167499Y149550D03*
X163499Y140050D03*
X160999Y149550D03*
X166800Y240800D03*
X158999Y259800D03*
X152808Y246341D03*
X157740Y273924D03*
X167299Y369350D03*
X150699Y411050D03*
X152499Y395950D03*
X149700Y471600D03*
X154100Y476500D03*
X164600Y476700D03*
X153499Y502550D03*
X148999D03*
X154099Y529236D03*
X162500Y623400D03*
X152400Y643300D03*
X152124Y651868D03*
X159054Y665400D03*
X161999Y843550D03*
Y848050D03*
X156499Y846050D03*
X156999Y850050D03*
X156499Y870550D03*
Y876050D03*
X163999Y863050D03*
X159999D03*
X155999Y859050D03*
Y863050D03*
X158114Y883290D03*
X156499Y886950D03*
X159459Y896616D03*
X163499Y896550D03*
X155499Y891050D03*
Y896050D03*
X157499Y904550D03*
Y909050D03*
X153299Y943750D03*
X156499Y985950D03*
X149499Y997650D03*
X162499Y1023550D03*
X158300Y1015000D03*
X163499Y1035050D03*
X159499Y1044579D03*
X165600Y1057428D03*
X168099Y1083550D03*
X164999Y1075550D03*
X159055Y1070400D03*
X167999Y1092850D03*
X167499Y1118550D03*
X167999Y1130550D03*
X163499Y1171650D03*
X151699Y1158550D03*
X151499Y1173050D03*
X150999Y1181150D03*
X148499Y1222113D03*
Y1226113D03*
X148486Y1230113D03*
X167499Y1389050D03*
X156999Y1397750D03*
X166799Y1409350D03*
X157915Y1420460D03*
X163499Y1433350D03*
X165499Y1453550D03*
X166799Y1487450D03*
X159054Y1476200D03*
X157500Y1797400D03*
X158000Y1825400D03*
X157999Y1840972D03*
X167200Y1868000D03*
X159054Y1855050D03*
X163599Y1892050D03*
X168299Y1879850D03*
X159054Y1881800D03*
X159173Y1935972D03*
X148499Y1977250D03*
X163500Y1987500D03*
X189499Y4550D03*
Y39150D03*
X183499Y45550D03*
X168499Y65550D03*
X176499Y140050D03*
X177899Y199250D03*
X185999Y250550D03*
X181299Y267350D03*
X187199Y359050D03*
X181599Y396250D03*
X168999Y413050D03*
X188499Y413550D03*
X179999Y442550D03*
X179649Y438550D03*
X183999D03*
Y442550D03*
Y447050D03*
X179999D03*
X171300Y476700D03*
X181999Y624050D03*
Y609550D03*
Y641550D03*
X182599Y688350D03*
X171999Y672450D03*
X170799Y689150D03*
X178899Y765250D03*
X172599Y774250D03*
X168499Y846713D03*
X173899Y846550D03*
X172099Y877450D03*
X169299Y956350D03*
X171499Y998650D03*
X169299Y1067150D03*
X171599Y1139950D03*
X180400Y1202800D03*
X181700Y1219900D03*
X179800Y1244100D03*
X179500Y1262000D03*
X178200Y1393400D03*
X180599Y1424050D03*
X180000Y1439500D03*
X176599Y1447450D03*
X172299Y1465850D03*
X181500Y1479000D03*
X176299Y1500150D03*
X180299Y1626550D03*
X180000Y1619600D03*
X180299Y1634550D03*
X179733Y1630590D03*
X181900Y1675300D03*
X180701Y1716050D03*
X179701Y1724550D03*
X180000Y1731000D03*
X185999Y1746050D03*
X182299Y1801350D03*
X173899Y1813250D03*
X177599Y1866750D03*
X168499Y1855550D03*
X181099Y1885850D03*
X168699Y1957150D03*
X183999Y1968150D03*
X188199Y1978250D03*
X183000Y1987500D03*
X206999Y5050D03*
X197999Y39900D03*
X193999D03*
X208499Y45650D03*
X199999Y46050D03*
X194499Y44050D03*
X191999Y68050D03*
X192499Y57550D03*
X206899Y171650D03*
X190199Y178650D03*
X191999Y221550D03*
X203499Y250550D03*
X201199Y266750D03*
X209199Y365050D03*
X209499Y412550D03*
X209999Y426150D03*
X194999Y490050D03*
X190499Y487550D03*
X191199Y491550D03*
X205300Y508100D03*
X190499Y507513D03*
X206499Y623550D03*
Y609050D03*
X207300Y639400D03*
X199199Y659150D03*
X190399Y689050D03*
X209500Y759000D03*
X208799Y766750D03*
X190699Y778350D03*
X197099Y795050D03*
X208299Y805350D03*
X202900Y811900D03*
X198199Y805950D03*
X204496Y846111D03*
X204649Y838050D03*
X208999D03*
X209000Y846113D03*
X204649Y842113D03*
X208986D03*
X198499Y884113D03*
X204699Y929450D03*
X206699Y953050D03*
X203999Y943350D03*
X205999Y978250D03*
X206299Y990250D03*
X207299Y1008150D03*
X202100Y1028100D03*
X199499Y1093850D03*
X209900Y1093600D03*
X208199Y1145850D03*
X210199Y1173450D03*
X204199Y1163850D03*
X201600Y1205900D03*
X196499Y1215550D03*
Y1196550D03*
X196399Y1236650D03*
X196499Y1224550D03*
X195499Y1251050D03*
X202199Y1276850D03*
X195499Y1279050D03*
Y1270050D03*
X202899Y1291450D03*
X207699Y1337950D03*
X195500Y1352500D03*
X208049Y1385550D03*
X203199Y1393250D03*
X204699Y1418350D03*
X201000Y1408500D03*
X194200Y1457900D03*
X204999Y1472650D03*
X208999Y1491250D03*
X202399Y1500750D03*
X195700Y1619100D03*
X195600Y1623700D03*
X209200Y1624000D03*
X200600Y1663600D03*
X199900Y1670600D03*
X193499Y1674050D03*
X197600Y1694900D03*
X204400Y1688200D03*
X209901Y1691850D03*
X201801Y1701450D03*
X195001Y1708150D03*
X205200Y1708000D03*
X195500Y1717000D03*
X195000Y1725500D03*
X206900Y1726700D03*
X199699Y1761450D03*
X205199Y1801950D03*
X209999Y1825050D03*
X192100Y1813500D03*
X204399Y1855450D03*
X206999Y1867550D03*
X207199Y1892850D03*
X191599Y1891550D03*
X199599Y1879850D03*
X205499Y1968650D03*
X190199Y1957650D03*
X199600Y1974900D03*
X209699Y1978750D03*
X199000Y1987500D03*
X226499Y5050D03*
X225499Y52550D03*
Y46550D03*
Y63550D03*
Y58050D03*
X229099Y161350D03*
X210999Y221550D03*
X217999Y250550D03*
X223799Y365350D03*
X217599Y396450D03*
X218499Y474850D03*
X224299Y494650D03*
X220499Y560050D03*
Y545550D03*
Y577550D03*
X224999Y613450D03*
X219999Y632550D03*
Y647050D03*
X226399Y677550D03*
X212999Y677350D03*
X218800Y668700D03*
X224099Y770250D03*
X214799Y774750D03*
X227199Y795050D03*
X217300Y816800D03*
X215999Y887550D03*
X220499D03*
X215499Y883550D03*
X225299Y957650D03*
X213999Y958650D03*
X217499Y981050D03*
X216999Y967550D03*
X217499Y998550D03*
X217999Y1012050D03*
X215999Y1039550D03*
X216499Y1053050D03*
X214499Y1154250D03*
X223099Y1182750D03*
X212499Y1184550D03*
Y1212550D03*
X221599Y1237250D03*
X220999Y1224350D03*
X222299Y1251850D03*
X229899Y1250550D03*
X211499Y1258050D03*
Y1239050D03*
X216300Y1274800D03*
X211499Y1267050D03*
X219099Y1325950D03*
X226599Y1340250D03*
X213199Y1350050D03*
X227399Y1363050D03*
X217499Y1387450D03*
X230599Y1400250D03*
X217999Y1408850D03*
X227999Y1421550D03*
X226300Y1447800D03*
X230899Y1437350D03*
X212400Y1433700D03*
X213399Y1500300D03*
X212899Y1535550D03*
X230999D03*
X211999Y1568550D03*
X231499Y1575050D03*
X224499D03*
X217999Y1574550D03*
X211999D03*
X218000Y1614300D03*
X228999Y1637550D03*
X211999Y1653550D03*
X230600Y1670500D03*
X213000Y1672500D03*
X216601Y1684350D03*
X226800Y1684200D03*
X220100Y1691700D03*
X212000Y1701300D03*
X222700Y1710100D03*
X222499Y1743850D03*
X221499Y1760950D03*
X220799Y1791550D03*
X215299Y1813950D03*
X224800Y1867000D03*
X228999Y1856050D03*
X212399Y1885850D03*
X227499Y1971050D03*
X221300Y1971200D03*
X225199Y1978750D03*
X216999Y1987550D03*
X241999Y5050D03*
X247499Y37550D03*
X246999Y46550D03*
Y56050D03*
X247499Y65050D03*
X244499Y136550D03*
Y122050D03*
X244900Y149100D03*
X232400Y220700D03*
X249800Y248800D03*
X235399Y263350D03*
X237699Y426050D03*
X232999Y414550D03*
X252499Y415050D03*
X251499Y446050D03*
X231999Y445550D03*
X251999Y462050D03*
X232499Y461550D03*
X244199Y483350D03*
X242099Y511750D03*
X244999Y559550D03*
Y545050D03*
Y577050D03*
X244499Y632050D03*
X246500Y663300D03*
X245000Y647000D03*
X234200Y668300D03*
X245599Y773450D03*
X234299Y773750D03*
X247099Y795050D03*
X233799Y806350D03*
X245399Y823550D03*
X244099Y857450D03*
X252399Y838250D03*
X245199Y878050D03*
X232399Y886550D03*
X252899Y886350D03*
X245399Y907450D03*
X243899Y923650D03*
X242199Y938750D03*
X252499Y948850D03*
X244199Y973250D03*
X232299Y981950D03*
X233499Y966050D03*
X245899Y995250D03*
X233999Y997050D03*
Y1012550D03*
X232499Y1038050D03*
X249499Y1104150D03*
X232599Y1195750D03*
X251999Y1184550D03*
X242199Y1210050D03*
X242599Y1198350D03*
X247899Y1208650D03*
X234299Y1232650D03*
X250900Y1248500D03*
X242900Y1263000D03*
X232799Y1276150D03*
X241399Y1303250D03*
X239099Y1314150D03*
X252399Y1326350D03*
X245999Y1339050D03*
Y1358050D03*
X234300Y1375700D03*
X246499Y1370050D03*
X249800Y1388400D03*
X244999Y1412550D03*
X245499Y1424550D03*
X238899Y1453750D03*
X248000Y1482000D03*
X250199Y1473550D03*
X247500Y1499000D03*
X236999Y1535550D03*
X238300Y1575100D03*
X246200Y1617600D03*
X239400Y1624300D03*
X242999Y1658050D03*
X237400Y1663800D03*
X235499Y1697050D03*
X249199Y1743150D03*
X237999Y1730550D03*
X244999Y1755050D03*
X252199Y1793050D03*
X238699Y1801850D03*
X241199Y1867150D03*
X244700Y1878700D03*
X241255Y1896055D03*
X238999Y1970550D03*
X232999Y1971050D03*
X240900Y1979000D03*
X236500Y1987500D03*
X261499Y4550D03*
X253999Y48050D03*
X264999Y55350D03*
X261299Y75950D03*
X258699Y104550D03*
X265299Y96250D03*
X262299Y164050D03*
X262699Y208550D03*
X271999Y216050D03*
X265999Y245050D03*
X258999Y396650D03*
X266699Y425050D03*
X269999Y415050D03*
X272499Y445050D03*
X266199Y472350D03*
X272999Y461050D03*
X257499Y498050D03*
Y512550D03*
Y530050D03*
X256499Y577050D03*
Y591550D03*
Y609050D03*
X269499Y616550D03*
X257199Y640050D03*
X269499Y631050D03*
Y648550D03*
X268099Y795450D03*
X254699Y807650D03*
X264499Y829050D03*
X264999Y842550D03*
Y858450D03*
X265799Y901850D03*
X256199Y916250D03*
X254899Y929250D03*
X253499Y938050D03*
X269599Y923950D03*
X267199Y935350D03*
X264799Y946850D03*
X263299Y959350D03*
X272999Y981050D03*
Y965550D03*
X256499Y967050D03*
X262499Y995850D03*
X254499Y984550D03*
X258999Y1011550D03*
X269999Y1037050D03*
X253499Y1038550D03*
X269999Y1052550D03*
X253999Y1052050D03*
X272999Y1102850D03*
X262499Y1129150D03*
X260349Y1139200D03*
X272999Y1214150D03*
X261199Y1227950D03*
X264800Y1261300D03*
X254899Y1289950D03*
X264799Y1313850D03*
X265299Y1339650D03*
X263699Y1359550D03*
X265499Y1376950D03*
X258999Y1396950D03*
X270599Y1408550D03*
X259299Y1438750D03*
X268499Y1453550D03*
X265700Y1635100D03*
X258700Y1645100D03*
X270999Y1660550D03*
X253999Y1676550D03*
X273499Y1694050D03*
X255699Y1722550D03*
X256499Y1710050D03*
X263499Y1734550D03*
X270599Y1748950D03*
X259499Y1760650D03*
X270599Y1801450D03*
X253899Y1813250D03*
X261499Y1825050D03*
X255999Y1855950D03*
X270299Y1867250D03*
X254500Y1987500D03*
X272000D03*
X278999Y5050D03*
X292999Y4550D03*
X294100Y28000D03*
X289499Y39050D03*
X286603Y34928D03*
X289999Y72550D03*
X290999Y67550D03*
X288499Y76550D03*
X289499Y80550D03*
X283599Y106250D03*
X274700Y131500D03*
X280999Y120050D03*
Y152050D03*
X290999Y216050D03*
X283499Y245050D03*
X277799Y338599D03*
X293998Y361114D03*
Y356614D03*
Y352114D03*
X289998Y361114D03*
Y356614D03*
Y352114D03*
X276299Y376050D03*
X289399Y395750D03*
X284499Y415050D03*
X291599Y446150D03*
X286999Y462050D03*
X281999Y497550D03*
X292999Y483550D03*
X281999Y512050D03*
Y529550D03*
X277999Y545350D03*
X280999Y576550D03*
Y591050D03*
Y608550D03*
X293999Y616050D03*
Y630550D03*
Y648050D03*
X294999Y767050D03*
X290999D03*
X294999Y762550D03*
Y758050D03*
X290999Y762550D03*
Y758050D03*
X287799Y794850D03*
X275299Y806350D03*
X288899Y820550D03*
X280999Y827550D03*
X283599Y857450D03*
X293899Y843850D03*
X280999Y843050D03*
Y870050D03*
X281499Y883550D03*
X274299Y912950D03*
X287299Y901050D03*
X281099Y943550D03*
X278799Y956150D03*
X290099Y948650D03*
X289399Y963350D03*
X277599Y975250D03*
X288099Y971250D03*
X285399Y982950D03*
X294699Y989550D03*
X287099Y1000150D03*
X274999Y996550D03*
X289699Y1021750D03*
X275099Y1024750D03*
X274999Y1012050D03*
X287099Y1035050D03*
X282999Y1099550D03*
X274900Y1115600D03*
X290699Y1122650D03*
X283499Y1113050D03*
X276299Y1134550D03*
X283299Y1144850D03*
X291399Y1174150D03*
X279799Y1191750D03*
X286599Y1203750D03*
X283799Y1249250D03*
X274299Y1276450D03*
X281099Y1302850D03*
X286799Y1326450D03*
X286499Y1364050D03*
Y1345050D03*
X278799Y1386250D03*
X285499Y1399550D03*
X278000Y1422000D03*
X285499Y1418550D03*
Y1427550D03*
X286600Y1449700D03*
X286700Y1516100D03*
X293998Y1573614D03*
Y1569114D03*
X289998Y1573614D03*
Y1569114D03*
X293998Y1578114D03*
X289998D03*
X278499Y1621550D03*
X289000Y1641800D03*
X284300Y1676900D03*
X291099Y1707450D03*
X280499Y1718550D03*
X285499Y1742550D03*
X290699Y1760750D03*
X286599Y1791850D03*
X284299Y1811150D03*
X295299Y1870250D03*
X283999Y1856050D03*
X293999Y1971050D03*
Y1966550D03*
Y1962050D03*
X289499Y1961550D03*
Y1966550D03*
Y1971050D03*
X291499Y1987550D03*
X310499Y5050D03*
X304500Y44500D03*
X303300Y39500D03*
X308700Y39800D03*
X308800Y46400D03*
X306999Y55450D03*
X311299D03*
X315799Y55350D03*
X308499Y72550D03*
X303999Y74050D03*
X307999Y78550D03*
X306100Y126500D03*
X307199Y205550D03*
X310499Y216550D03*
X297999Y245050D03*
X313199Y270350D03*
X313000Y313900D03*
X305998Y352114D03*
X299899Y376650D03*
X310999Y396250D03*
X300899Y431850D03*
X303999Y415550D03*
X306100Y462000D03*
X312499Y484050D03*
X298599Y501250D03*
X309399Y513450D03*
X297599Y519350D03*
X307499Y555550D03*
Y541050D03*
X297499Y551050D03*
X296199Y568550D03*
X307499Y573050D03*
X302899Y607950D03*
X307499Y661550D03*
Y647050D03*
X297699Y681850D03*
X307499Y679050D03*
X308899Y705150D03*
X298399Y703450D03*
X296399Y716950D03*
X306999Y758050D03*
X314499Y754550D03*
X307999Y803150D03*
X307899Y794550D03*
X300199Y835250D03*
X304899Y856150D03*
X313499Y847850D03*
X315199Y869450D03*
X297499Y868550D03*
X302499Y899050D03*
X297499Y884050D03*
X302199Y914650D03*
X315199Y925950D03*
X310699Y943550D03*
X299399Y965950D03*
X298099Y977250D03*
X307999Y970650D03*
X306699Y981250D03*
X304399Y997550D03*
X298399Y1008150D03*
X306399Y1020750D03*
X303699Y1038050D03*
X299999Y1052350D03*
X304699Y1057050D03*
X312299Y1093550D03*
X299499Y1098050D03*
Y1113550D03*
X316499Y1124550D03*
X307999Y1142050D03*
X304499Y1156650D03*
X313499Y1170150D03*
X300699Y1185150D03*
X315408Y1202663D03*
X311999Y1213850D03*
X300699Y1227350D03*
X310299Y1240050D03*
X304699Y1265850D03*
X312499Y1280350D03*
X295399Y1292950D03*
X300499Y1305350D03*
X311500Y1316300D03*
X297899Y1336150D03*
X298099Y1357250D03*
X311900Y1344900D03*
X301699Y1377950D03*
X312900Y1366900D03*
X301699Y1395750D03*
X313600Y1391300D03*
X303499Y1411250D03*
X312100Y1420700D03*
X300899Y1433350D03*
X313600Y1442700D03*
X304699Y1457550D03*
X312800Y1467400D03*
X296599Y1497150D03*
X312000Y1514600D03*
X305998Y1569114D03*
X307000Y1619600D03*
X302399Y1662950D03*
X299999Y1696050D03*
X303999Y1722050D03*
X297099Y1733850D03*
X303499Y1753550D03*
X303999Y1800850D03*
X315499Y1812250D03*
X298999Y1855950D03*
X313599Y1870250D03*
X308099Y1880550D03*
X313599Y1889250D03*
X314099Y1901250D03*
X305999Y1913050D03*
X302499Y1922050D03*
X296858Y1956228D03*
X305999Y1964050D03*
Y1969550D03*
X311500Y1987500D03*
X329999Y5050D03*
X332200Y94200D03*
X321799Y173950D03*
X317499Y192950D03*
X331499Y193250D03*
X325499Y249450D03*
X337499Y282550D03*
X316999Y312576D03*
X321748Y343299D03*
X328799Y372350D03*
X336099Y417550D03*
X322099Y426850D03*
X324999Y414550D03*
X328599Y442250D03*
X327900Y463200D03*
X333499Y483050D03*
X329999Y510450D03*
X321999Y533150D03*
X331999Y555050D03*
Y540550D03*
X321999Y550550D03*
X321299Y565250D03*
X320799Y582050D03*
X331999Y572550D03*
X328599Y602450D03*
X328499Y635650D03*
X317999Y627850D03*
X331999Y661050D03*
Y646550D03*
Y678550D03*
X324599Y696150D03*
X330799Y712450D03*
X318999Y814350D03*
X325599Y823950D03*
X330299Y871850D03*
X323799Y859850D03*
X321099Y899650D03*
X323099Y885050D03*
X322099Y913650D03*
X331099Y923650D03*
X328099Y937250D03*
X323499Y956950D03*
X329799Y970650D03*
X333099Y983450D03*
X320999Y997250D03*
X331299Y1017150D03*
X321299Y1012450D03*
Y1024750D03*
X331599Y1028750D03*
X329599Y1040750D03*
X318299Y1038750D03*
X329599Y1057050D03*
X319999Y1066950D03*
X317699Y1054650D03*
X329299Y1098550D03*
X326599Y1112350D03*
X332999Y1123050D03*
X323999Y1153250D03*
X332999Y1138550D03*
X317999Y1137550D03*
X329799Y1182750D03*
X328999Y1200550D03*
X326649Y1227850D03*
Y1218850D03*
X327999Y1255050D03*
X333349Y1270500D03*
Y1288900D03*
Y1307000D03*
Y1332800D03*
Y1363500D03*
Y1393100D03*
Y1429500D03*
Y1481900D03*
X332500Y1519700D03*
X337199Y1636350D03*
X320299Y1642950D03*
X316799Y1657450D03*
X335767Y1662735D03*
X318499Y1675550D03*
X334399Y1691650D03*
X329999Y1716950D03*
X320999Y1706050D03*
X321999Y1733050D03*
X321499Y1772550D03*
X327299Y1791850D03*
X322299Y1802150D03*
X337499Y1855950D03*
X316999D03*
X336799Y1869950D03*
X326399Y1876250D03*
X336799Y1888950D03*
X326899Y1907250D03*
X326399Y1895250D03*
X336799Y1897950D03*
X335799Y1916450D03*
X326799Y1977050D03*
X329999Y1987550D03*
X345499Y5050D03*
X356499Y113050D03*
X351999D03*
X347499D03*
X355999Y100550D03*
X350999D03*
X345999D03*
X354099Y175350D03*
X343399Y161350D03*
X343999Y190050D03*
X343799Y204550D03*
X355499Y219050D03*
X337999D03*
X355999Y242750D03*
X343499Y253550D03*
X347699Y269050D03*
X354999Y282550D03*
X347399Y301950D03*
X339399Y358050D03*
X357999Y359050D03*
X354099Y373050D03*
X338399Y395650D03*
X338899Y433850D03*
X354699Y426650D03*
X356399Y451750D03*
X351399Y470750D03*
X340799Y512050D03*
X358399Y498650D03*
X341399Y535850D03*
X357399Y521250D03*
Y530550D03*
X341399Y558950D03*
X357399Y543850D03*
X357999Y559450D03*
X340299Y586550D03*
X342199Y613050D03*
X342099Y646350D03*
X341899Y664950D03*
X342599Y678850D03*
X345399Y698950D03*
X357699Y707750D03*
X341399Y715050D03*
X355999Y752850D03*
X353999Y787750D03*
X347699Y773450D03*
X338099Y811650D03*
X338599Y821650D03*
Y840450D03*
X340099Y887350D03*
X338399Y901050D03*
X340099Y910350D03*
X340399Y931250D03*
X340099Y952850D03*
X339599Y1081550D03*
X344399Y1338150D03*
X343599Y1360050D03*
X344099Y1393750D03*
Y1421150D03*
Y1449550D03*
X351899Y1570850D03*
X344500Y1583600D03*
X350600Y1610900D03*
X349099Y1634550D03*
X351099Y1691150D03*
X352000Y1700400D03*
X343899Y1752650D03*
X357999Y1796050D03*
X355699Y1810750D03*
X351999Y1855450D03*
X348999Y1879050D03*
X349499Y1910050D03*
X348999Y1898050D03*
X347999Y1925550D03*
X348499Y1956550D03*
X347999Y1944550D03*
X347699Y1972250D03*
X345499Y1987550D03*
X364999Y4550D03*
X371999Y15550D03*
X376499D03*
X369999Y23550D03*
Y19050D03*
X360999Y113050D03*
Y100550D03*
X363999Y136050D03*
Y121550D03*
Y153550D03*
X362999Y190050D03*
X369999Y219050D03*
X362499Y253550D03*
X369499Y282550D03*
X359399Y307250D03*
X368299Y386350D03*
X359399Y576050D03*
Y599650D03*
X360399Y615550D03*
X359699Y627550D03*
X358899Y657150D03*
X359399Y669450D03*
X359199Y690650D03*
X377499Y1182050D03*
Y1210050D03*
Y1201050D03*
X376499Y1236550D03*
Y1255550D03*
Y1264550D03*
X376599Y1293950D03*
X375599Y1323350D03*
X374499Y1347550D03*
Y1375550D03*
Y1366550D03*
X373499Y1402050D03*
Y1421050D03*
X376299Y1437650D03*
X373499Y1430050D03*
X373099Y1456550D03*
X374799Y1491250D03*
X374099Y1554550D03*
X376099Y1572850D03*
X375099Y1608250D03*
X377700Y1629000D03*
X374999Y1656750D03*
X377099Y1696350D03*
X359499Y1736850D03*
X376799Y1734050D03*
X376499Y1775550D03*
X369499Y1855950D03*
X359999Y1878550D03*
X369799Y1880050D03*
X359999Y1897550D03*
Y1906550D03*
X369999Y1901950D03*
X358999Y1925050D03*
X369199Y1919750D03*
X367299Y1956950D03*
X367999Y1940250D03*
X367299Y1972950D03*
X364999Y1987050D03*
X382499Y5050D03*
X395999Y5550D03*
X380999Y15550D03*
X382499Y20050D03*
X389599Y90950D03*
X380599Y103550D03*
X381299Y136750D03*
X400499Y134050D03*
Y119550D03*
Y151550D03*
X389299Y161650D03*
X382499Y190550D03*
X387599Y220150D03*
X385999Y207250D03*
X381999Y254050D03*
X382999Y276650D03*
X386899Y299250D03*
X383299Y310250D03*
X386599Y348450D03*
X394899Y357750D03*
X380599Y381050D03*
X380099Y1709650D03*
X393499Y1759550D03*
X393999Y1784550D03*
X387899Y1802850D03*
X391499Y1855950D03*
X389499Y1885050D03*
Y1913050D03*
Y1904050D03*
X388499Y1932950D03*
Y1950550D03*
X385099Y1975950D03*
X399299Y1976750D03*
X388499Y1959550D03*
X382499Y1987550D03*
X413499Y6050D03*
X416999Y25050D03*
X417499Y46550D03*
X416999Y63550D03*
X417499Y79050D03*
Y93550D03*
Y108050D03*
Y125550D03*
X416999Y145050D03*
Y164050D03*
X417999Y185050D03*
X412999Y275550D03*
Y307550D03*
Y290050D03*
X422199Y363350D03*
X420199Y391350D03*
X415099Y422550D03*
X410799Y431150D03*
X419599Y458550D03*
X415999Y518550D03*
X420199Y638550D03*
X418799Y877050D03*
Y896050D03*
X409499Y1102550D03*
X419999Y1115550D03*
X415499Y1161550D03*
X416099Y1183550D03*
X415499Y1176050D03*
X419499Y1234050D03*
Y1219550D03*
X420099Y1241550D03*
X416699Y1342650D03*
X416199Y1367550D03*
X414799Y1532350D03*
X418299Y1561250D03*
X415999Y1603250D03*
X416199Y1625250D03*
X414799Y1653750D03*
X414399Y1678350D03*
X414499Y1707250D03*
X410757Y1772872D03*
X417799Y1790850D03*
X414499Y1810450D03*
X406999Y1855950D03*
X421399Y1888050D03*
X406499Y1893050D03*
Y1874050D03*
X421399Y1907050D03*
X406999Y1905050D03*
X420399Y1934550D03*
X421399Y1916050D03*
X405499Y1920550D03*
X420399Y1953550D03*
X405999Y1951550D03*
X405499Y1939550D03*
X420399Y1962550D03*
X420799Y1977250D03*
X420500Y1987000D03*
X403500D03*
X432999Y6050D03*
X436499Y31350D03*
Y50350D03*
X437499Y71350D03*
X441799Y102450D03*
Y121450D03*
X442799Y142450D03*
X430499Y217050D03*
X423799Y259750D03*
X437499Y275050D03*
Y307050D03*
Y289550D03*
X422499Y348150D03*
X438999Y381550D03*
X426599Y415350D03*
X443199Y440850D03*
X440099Y459250D03*
X431099Y479350D03*
X435499Y519050D03*
X430099Y551450D03*
X427999Y580050D03*
Y565550D03*
Y597550D03*
X427499Y624550D03*
X437299Y744650D03*
X435299Y763150D03*
X424999Y766550D03*
X435299Y777650D03*
X422999Y785050D03*
X434799Y814650D03*
X435299Y795150D03*
X422999Y799550D03*
X434799Y833650D03*
X422999Y817050D03*
X422499Y855550D03*
Y836550D03*
X442599Y905650D03*
Y924650D03*
X423299Y994050D03*
Y1013050D03*
X424299Y1034050D03*
X432599Y1064550D03*
X433599Y1085550D03*
X428999Y1102550D03*
X439499Y1115550D03*
X436999Y1128050D03*
X437599Y1150050D03*
X436999Y1142550D03*
X443199Y1224250D03*
Y1238750D03*
X424999Y1278550D03*
Y1259550D03*
X425499Y1290550D03*
X428499Y1325350D03*
X434499Y1360250D03*
X422299Y1394950D03*
X441499Y1399550D03*
X426799Y1416050D03*
X441499Y1414050D03*
X423299Y1430350D03*
X425799Y1447950D03*
X441499Y1431550D03*
X427099Y1469150D03*
X424299Y1541350D03*
X439599Y1552150D03*
X434500Y1579500D03*
X432499Y1617550D03*
X431999Y1605550D03*
X425499Y1635050D03*
X432400Y1680100D03*
X427499Y1662050D03*
X428600Y1691200D03*
X435300Y1715300D03*
X429499Y1748050D03*
X441499Y1758050D03*
X436799Y1772550D03*
X422999Y1778550D03*
X426499Y1855450D03*
X434299Y1876050D03*
Y1904050D03*
Y1895050D03*
X433299Y1922550D03*
Y1950550D03*
Y1941550D03*
X436299Y1977250D03*
X438999Y1987550D03*
X448499Y6050D03*
X445799Y165650D03*
Y184650D03*
X446799Y205650D03*
X449999Y217050D03*
X448999Y255550D03*
X444499Y283050D03*
X463999Y283550D03*
X443499Y354050D03*
X464499Y353050D03*
X458499Y382050D03*
X450300Y404200D03*
X453999Y417550D03*
X454999Y438550D03*
X454499Y472550D03*
Y458050D03*
Y490050D03*
X456499Y518050D03*
X453999Y509550D03*
X452499Y579550D03*
Y565050D03*
Y597050D03*
X463999Y659550D03*
X450399Y672750D03*
X444799Y687350D03*
X463999Y674050D03*
Y691550D03*
X451099Y711650D03*
X452099Y762450D03*
Y781450D03*
X453399Y807950D03*
Y826950D03*
X462999Y865050D03*
Y884050D03*
X464499Y896050D03*
X462499Y914550D03*
Y929050D03*
X443599Y945650D03*
X462499Y946550D03*
X461999Y966050D03*
Y985050D03*
X462499Y1043850D03*
Y1062850D03*
X463499Y1083850D03*
X463999Y1102050D03*
X444499Y1102550D03*
X454999Y1115550D03*
X453499Y1140550D03*
X454499Y1161550D03*
X443799Y1246250D03*
Y1274250D03*
Y1265250D03*
X448099Y1341250D03*
X444899Y1377950D03*
X464199Y1401450D03*
X459999Y1424050D03*
X456399Y1445950D03*
X459699Y1468050D03*
X445099Y1464250D03*
X444299Y1532650D03*
X461399Y1541650D03*
X452199Y1550650D03*
X449199Y1579050D03*
X443799Y1612250D03*
X460199Y1632850D03*
X449599Y1656950D03*
X448399Y1699450D03*
X447699Y1682850D03*
X458499Y1742050D03*
X463999Y1772050D03*
X445499Y1792550D03*
X448099Y1809450D03*
X443999Y1855950D03*
X460299Y1892350D03*
X446999Y1880050D03*
X460299Y1911350D03*
X446999Y1908050D03*
Y1899050D03*
X460299Y1920350D03*
X445999Y1926550D03*
X459299Y1938850D03*
X445999Y1954550D03*
Y1945550D03*
X459299Y1966850D03*
Y1957850D03*
X455799Y1976750D03*
X456500Y1987500D03*
X467999Y5550D03*
X485499Y6050D03*
X465799Y24750D03*
Y43750D03*
X466799Y64750D03*
X470399Y84550D03*
Y103550D03*
X471399Y124550D03*
X473099Y141050D03*
X483599Y179350D03*
X473099Y160050D03*
X474099Y181050D03*
X472999Y214550D03*
X469999Y254550D03*
X481499Y283550D03*
X466399Y304950D03*
X479299Y297250D03*
X483499Y353050D03*
X485000Y373200D03*
X484900Y394700D03*
X468799Y414250D03*
X472499Y458050D03*
X471499Y493950D03*
X485299Y534550D03*
X479999Y581050D03*
Y566550D03*
Y598550D03*
X472999Y736550D03*
X467699Y772750D03*
X468699Y788350D03*
X479599Y847550D03*
X475699Y880450D03*
X483499Y1064850D03*
X484499Y1085850D03*
X481499Y1102550D03*
X474499Y1115050D03*
X473099Y1144550D03*
X474099Y1165550D03*
X465499Y1265550D03*
Y1284550D03*
Y1293550D03*
X468999Y1323950D03*
X473999Y1342450D03*
X468699Y1362850D03*
X485599Y1367550D03*
X466699Y1378150D03*
X481499Y1402550D03*
Y1417050D03*
X482599Y1449950D03*
X478299Y1464850D03*
X466999Y1530650D03*
X474299Y1544750D03*
X472299Y1572050D03*
X484200Y1579900D03*
X465999Y1603450D03*
X472499Y1611550D03*
X484999Y1636550D03*
X472499Y1620550D03*
X483599Y1662550D03*
X467999Y1668050D03*
X485599Y1694850D03*
X467999Y1687050D03*
Y1696050D03*
X468499Y1712550D03*
X480999Y1756050D03*
X484999Y1779050D03*
X472699Y1792150D03*
X481299Y1811150D03*
X480499Y1855450D03*
X464999D03*
X476199Y1877450D03*
Y1905450D03*
Y1896450D03*
X475199Y1923950D03*
Y1951950D03*
Y1942950D03*
X473299Y1977250D03*
X476000Y1987000D03*
X498999Y6050D03*
X499999Y25550D03*
X500499Y47050D03*
X499999Y64050D03*
X500499Y79550D03*
Y94050D03*
Y108550D03*
Y126050D03*
X499999Y145550D03*
Y164550D03*
X504199Y193250D03*
X502899Y217150D03*
X488999Y254550D03*
X495999Y283550D03*
X502999Y353550D03*
X490999Y412550D03*
X503699Y419250D03*
X490999Y427050D03*
Y444550D03*
X498399Y470050D03*
X490499Y464050D03*
Y483050D03*
X491499Y504050D03*
X504499Y580550D03*
Y566050D03*
Y598050D03*
X488499Y659050D03*
Y673550D03*
Y691050D03*
X506599Y711650D03*
X487299Y716950D03*
X490299Y734550D03*
X489599Y752450D03*
X495999Y795050D03*
X493999Y813550D03*
Y828050D03*
Y845550D03*
X493499Y865050D03*
Y884050D03*
X485799Y920050D03*
Y901050D03*
X486799Y941050D03*
X493099Y996350D03*
X494099Y1017350D03*
X501499Y1102550D03*
X491999Y1115550D03*
X504399Y1132250D03*
X505399Y1153250D03*
X486499Y1210550D03*
Y1196050D03*
X506599Y1202350D03*
Y1216850D03*
X487099Y1218050D03*
X498299Y1323350D03*
X499199Y1350550D03*
X498899Y1386450D03*
Y1408350D03*
X500899Y1434350D03*
X505899Y1466250D03*
X488299Y1531050D03*
X499699Y1538950D03*
X502199Y1566250D03*
X487099Y1606250D03*
X501399Y1634550D03*
X502899Y1709650D03*
X496999Y1799550D03*
X499999Y1854950D03*
X505799Y1893050D03*
X492999Y1878050D03*
X505799Y1912050D03*
X493499Y1909050D03*
X492999Y1897050D03*
X505799Y1921050D03*
X491999Y1924550D03*
X504799Y1939550D03*
X492499Y1955550D03*
X491999Y1943550D03*
X504799Y1967550D03*
Y1958550D03*
X493799Y1977250D03*
X492500Y1987500D03*
X516499Y6550D03*
X522899Y45350D03*
Y64350D03*
X523899Y85350D03*
X520299Y122450D03*
Y141450D03*
X521299Y162450D03*
X508499Y255050D03*
X525999D03*
X515499Y284050D03*
X516899Y306950D03*
X520499Y353550D03*
X509999Y382550D03*
X518999Y416550D03*
X511299Y449150D03*
X519499Y471550D03*
Y489050D03*
X508699Y498950D03*
X518999Y508550D03*
X514499Y546050D03*
X509999Y640550D03*
Y655050D03*
Y672550D03*
X527499Y747150D03*
X525499Y772450D03*
X511199Y782050D03*
X512899Y823550D03*
X526499Y851150D03*
X512899Y842550D03*
X510899Y868150D03*
X522499Y876050D03*
X521999Y895550D03*
X506899Y919950D03*
Y900950D03*
X521999Y914550D03*
X516499Y957050D03*
X514499Y975550D03*
Y990050D03*
Y1007550D03*
X513999Y1046050D03*
Y1027050D03*
X518999Y1103050D03*
X511999Y1115550D03*
X527499Y1181550D03*
X527999Y1212550D03*
X527499Y1200550D03*
X507199Y1224350D03*
X525999Y1231050D03*
X507199Y1252350D03*
Y1243350D03*
X525999Y1245550D03*
X527499Y1278150D03*
X525999Y1263050D03*
X518499Y1346950D03*
X523499Y1360050D03*
X508599Y1370550D03*
X523499Y1379050D03*
X523999Y1391050D03*
X516999Y1418050D03*
Y1437050D03*
X517499Y1449050D03*
X518899Y1530150D03*
X510100Y1579800D03*
X508199Y1610450D03*
X518499Y1643950D03*
X509199Y1660550D03*
X507399Y1683350D03*
X522300Y1739200D03*
X508200Y1758200D03*
X515499Y1779050D03*
X526499Y1801150D03*
X514199Y1815750D03*
X517499Y1855450D03*
X519399Y1876750D03*
Y1904750D03*
Y1895750D03*
X518399Y1923250D03*
Y1951250D03*
Y1942250D03*
X509299Y1977250D03*
X511999Y1987550D03*
X535999Y6550D03*
X541499Y25050D03*
X541999Y46550D03*
X541499Y63550D03*
X541999Y79050D03*
Y93550D03*
Y108050D03*
Y125550D03*
X541499Y145050D03*
Y164050D03*
X528799Y199950D03*
X542499Y185050D03*
X533499Y217550D03*
X540499Y255050D03*
X536499Y283050D03*
X544799Y293950D03*
X540099Y306550D03*
X548100Y362200D03*
X530999Y381550D03*
X538799Y445050D03*
X539799Y466050D03*
X539299Y485550D03*
X535499Y545050D03*
X538999Y562050D03*
X534499Y640050D03*
Y654550D03*
Y672050D03*
X547999Y728550D03*
Y743050D03*
Y760550D03*
X547499Y780050D03*
X534499Y805950D03*
X547499Y799050D03*
X541399Y854450D03*
Y873450D03*
X539299Y935850D03*
X540299Y956850D03*
X540899Y981450D03*
Y1000450D03*
X541899Y1021450D03*
X534599Y1048550D03*
X535599Y1069550D03*
X538499Y1103050D03*
X548999Y1116050D03*
X529499D03*
X546499Y1180750D03*
Y1195250D03*
X547099Y1202750D03*
Y1230750D03*
Y1221750D03*
X548799Y1252850D03*
Y1267350D03*
X530499Y1297050D03*
X545099Y1355250D03*
X540399Y1382150D03*
X538799Y1409750D03*
X536799Y1436350D03*
X528499Y1460250D03*
X546099Y1467550D03*
X538999Y1528350D03*
X529799Y1555050D03*
X533800Y1575500D03*
X529499Y1616550D03*
X528999Y1604550D03*
X532499Y1635550D03*
X532599Y1655650D03*
X532499Y1669550D03*
Y1688550D03*
X532999Y1700550D03*
X538299Y1721050D03*
X532499Y1763050D03*
X539499Y1788150D03*
X531799Y1818450D03*
X538999Y1855950D03*
X547999Y1892350D03*
X533499Y1884050D03*
X547999Y1911350D03*
X533499Y1912050D03*
Y1903050D03*
X547999Y1920350D03*
X532499Y1930550D03*
X546999Y1938850D03*
X532499Y1949550D03*
X546999Y1966850D03*
Y1957850D03*
X546299Y1977250D03*
X528799Y1976750D03*
X532499Y1958550D03*
X531500Y1987500D03*
X551499Y6550D03*
X568099Y72550D03*
Y91550D03*
X569099Y112550D03*
X562799Y127750D03*
Y146750D03*
X563799Y167750D03*
X565999Y199950D03*
X568499Y217550D03*
X552999D03*
X555999Y412550D03*
X556499Y467550D03*
Y485050D03*
X555999Y504550D03*
X558499Y562550D03*
X565699Y710650D03*
X549999Y710050D03*
X562999Y898050D03*
X560999Y916550D03*
Y931050D03*
Y948550D03*
X560499Y968050D03*
Y987050D03*
X560999Y999050D03*
X558999Y1017550D03*
Y1032050D03*
X558499Y1069050D03*
X558999Y1049550D03*
X558499Y1088050D03*
X568499Y1101550D03*
X553999Y1103050D03*
X564499Y1116050D03*
X567999Y1187550D03*
Y1215550D03*
Y1206550D03*
X565999Y1234050D03*
Y1248550D03*
X566399Y1273850D03*
X549399Y1274850D03*
X561099Y1301050D03*
X549399Y1293850D03*
Y1302850D03*
X555699Y1322950D03*
X559099Y1343250D03*
X557499Y1424050D03*
Y1443050D03*
Y1452050D03*
X567999Y1549950D03*
X552199Y1576650D03*
X552099Y1601950D03*
X569499Y1610550D03*
X553399Y1624550D03*
X569499Y1619550D03*
X554199Y1651950D03*
X555199Y1674750D03*
X555399Y1689350D03*
X555899Y1706750D03*
X556199Y1727050D03*
X560399Y1792550D03*
X555500Y1802700D03*
X554499Y1855950D03*
X562599Y1893450D03*
Y1874450D03*
Y1902450D03*
X561599Y1920950D03*
Y1948950D03*
Y1939950D03*
X570299Y1976250D03*
X568999Y1987050D03*
X553499D03*
X570999Y6050D03*
X588499Y6550D03*
X587999Y25050D03*
X588499Y46550D03*
X587999Y63550D03*
X588499Y125550D03*
X587999Y145050D03*
Y164050D03*
X588999Y185050D03*
X587999Y217050D03*
X572999Y255050D03*
Y269550D03*
Y287050D03*
X572499Y306550D03*
Y325550D03*
X573499Y346550D03*
X579899Y375750D03*
X577399Y420050D03*
X578399Y441050D03*
X577899Y460550D03*
X576099Y481850D03*
X577099Y502850D03*
X576599Y522350D03*
X579499Y561550D03*
X573499Y658550D03*
Y673050D03*
Y690550D03*
X586299Y711250D03*
X577999Y732050D03*
X575999Y750550D03*
Y765050D03*
Y782550D03*
X575499Y802050D03*
Y821050D03*
X576499Y842050D03*
X578299Y895650D03*
Y914650D03*
X583299Y961450D03*
X570899Y946850D03*
X583299Y980450D03*
X570899Y965850D03*
X571899Y986850D03*
X573499Y1036550D03*
Y1055550D03*
X574499Y1076550D03*
X588499Y1101550D03*
X578999Y1114550D03*
X582699Y1233250D03*
X583299Y1255250D03*
X582699Y1247750D03*
X583299Y1274250D03*
X579299Y1300750D03*
X583299Y1283250D03*
X581999Y1370150D03*
X580999Y1412750D03*
X575699Y1438950D03*
X582999Y1461250D03*
X590599Y1483450D03*
X582299Y1534150D03*
X588099Y1572050D03*
X573400Y1577600D03*
X588000Y1604000D03*
X590799Y1627850D03*
X580799Y1646150D03*
X572999Y1675550D03*
X590599Y1694450D03*
X572999Y1694550D03*
Y1703550D03*
X580299Y1722550D03*
X582599Y1740050D03*
X573999Y1855450D03*
X588899Y1882350D03*
X575999Y1888050D03*
X588899Y1910350D03*
Y1901350D03*
X575999Y1907050D03*
X587899Y1928850D03*
X576499Y1919050D03*
X574999Y1934550D03*
X587899Y1956850D03*
Y1947850D03*
X574999Y1953550D03*
X585799Y1976250D03*
X575499Y1965550D03*
X588499Y1986550D03*
X608499Y6550D03*
X603999Y35350D03*
Y54350D03*
X604999Y75350D03*
X603999Y133750D03*
Y152750D03*
X604999Y173750D03*
X605499Y217550D03*
X599299Y344650D03*
X600299Y365650D03*
X599799Y385150D03*
X607399Y380250D03*
X592999Y407550D03*
Y422050D03*
Y439550D03*
X592499Y459050D03*
Y478050D03*
X593499Y499050D03*
X606499Y584550D03*
X595999Y624050D03*
Y609550D03*
Y641550D03*
X605299Y661750D03*
X609499Y708050D03*
X597999Y690050D03*
X607499Y726550D03*
Y741050D03*
Y758550D03*
X606999Y778050D03*
Y797050D03*
X603499Y904050D03*
X601499Y922550D03*
Y937050D03*
Y954550D03*
X600999Y1002050D03*
X611399Y1026650D03*
X598999Y1020550D03*
X611399Y1045650D03*
X598999Y1035050D03*
X612399Y1066650D03*
X598999Y1052550D03*
X598499Y1072050D03*
X605999Y1102050D03*
X598499Y1091050D03*
X598999Y1114550D03*
X603899Y1157850D03*
X597599Y1196050D03*
X596599Y1215050D03*
X600899Y1238650D03*
X598499Y1280550D03*
Y1261550D03*
X598999Y1292550D03*
X608899Y1305050D03*
X605599Y1326350D03*
X606199Y1338250D03*
X599499Y1351550D03*
X599999Y1382550D03*
X599499Y1370550D03*
X604899Y1407750D03*
X601299Y1447650D03*
X610899Y1496750D03*
X599799Y1544650D03*
X611900Y1577900D03*
X612499Y1615550D03*
X611999Y1603550D03*
X600599Y1645450D03*
X593399Y1668850D03*
X609499Y1675050D03*
Y1692050D03*
X607599Y1716450D03*
X606999Y1745550D03*
X593299Y1760950D03*
X608599Y1810750D03*
X595199Y1820910D03*
X611999Y1855950D03*
X591499D03*
X602799Y1887350D03*
Y1906350D03*
X601799Y1933850D03*
X602799Y1915350D03*
X601799Y1952850D03*
Y1961850D03*
X605299Y1975750D03*
X605999Y1987050D03*
X625999Y7050D03*
X624499Y23050D03*
X624999Y44550D03*
X624499Y61550D03*
X624999Y123550D03*
X624499Y143050D03*
Y162050D03*
X625499Y183050D03*
X623899Y202550D03*
X625499Y217550D03*
X627999Y262550D03*
Y248050D03*
Y280050D03*
X627499Y299550D03*
X628200Y320000D03*
X628499Y339550D03*
X632399Y358750D03*
X620999Y411550D03*
X621999Y432550D03*
X621499Y452050D03*
Y466550D03*
Y484050D03*
X613700Y504600D03*
X625999Y585050D03*
X620499Y623550D03*
Y609050D03*
X631999Y639650D03*
X622999Y672050D03*
Y689550D03*
X629099Y714050D03*
X633499Y750150D03*
X621499Y767150D03*
X621999Y835050D03*
X612999Y854550D03*
X629499Y853050D03*
Y868550D03*
X613499Y868050D03*
X616699Y948250D03*
Y967250D03*
X617699Y988250D03*
X631999Y1001550D03*
X629999Y1020050D03*
Y1034550D03*
Y1052050D03*
X629499Y1071550D03*
Y1090550D03*
X616499Y1115050D03*
X627699Y1143550D03*
X628699Y1164550D03*
X626199Y1183450D03*
X630499Y1243950D03*
X617599Y1246250D03*
X618199Y1268250D03*
X617599Y1260750D03*
X618199Y1296250D03*
Y1287250D03*
X631799Y1322650D03*
X617899Y1360850D03*
X632499Y1347950D03*
X625499Y1383450D03*
X627499Y1406050D03*
X626799Y1432350D03*
X625199Y1489150D03*
X617699Y1530350D03*
X623499Y1564050D03*
X633499Y1615450D03*
X628499Y1636650D03*
X627299Y1659550D03*
X625499Y1725050D03*
X619499Y1803150D03*
X627273Y1793905D03*
X626999Y1800050D03*
X632799Y1820450D03*
X627494Y1829068D03*
X627499Y1855950D03*
X630699Y1872750D03*
Y1891750D03*
Y1900750D03*
X616499Y1913050D03*
Y1894050D03*
X629699Y1919250D03*
X616499Y1922050D03*
X629699Y1947250D03*
Y1938250D03*
X615499Y1940550D03*
X622799Y1976250D03*
X615499Y1959550D03*
Y1968550D03*
X626999Y1987050D03*
X645499Y7050D03*
X651799Y40650D03*
Y59650D03*
X652799Y80650D03*
X649899Y138350D03*
Y157350D03*
X650899Y178350D03*
X642999Y218050D03*
X653999Y286550D03*
X635399Y376250D03*
X643599Y395950D03*
X644599Y416950D03*
X644099Y450950D03*
Y436450D03*
X642499Y525750D03*
X643499Y546750D03*
X642999Y566250D03*
X646999Y584550D03*
X640599Y604650D03*
X645099Y639150D03*
X647499Y657050D03*
Y671550D03*
X648999Y702350D03*
X647499Y689050D03*
X651999Y718350D03*
X647399Y742150D03*
X653099Y803350D03*
X645799Y816650D03*
X641599Y843250D03*
Y862250D03*
X642599Y883250D03*
X639499Y952150D03*
Y971150D03*
X633999Y1103050D03*
X641799Y1137650D03*
X650299Y1153150D03*
X651299Y1174150D03*
X650599Y1182050D03*
X651599Y1203050D03*
X638999Y1267550D03*
Y1286550D03*
Y1295550D03*
X654499Y1354050D03*
Y1373050D03*
X652999Y1403550D03*
Y1418050D03*
Y1435550D03*
X636799Y1461250D03*
X643099Y1541350D03*
X652399Y1575850D03*
X639200Y1576200D03*
X635500Y1603900D03*
X652499Y1618550D03*
Y1609550D03*
X649399Y1644950D03*
X635099Y1691150D03*
X642499Y1709050D03*
X650399Y1771250D03*
X642400Y1800100D03*
X633837Y1807384D03*
X640999Y1815550D03*
X644049Y1810834D03*
X645099Y1877550D03*
X645399Y1906150D03*
X646799Y1926450D03*
X644999Y1934050D03*
Y1953050D03*
X643799Y1976250D03*
X645499Y1965050D03*
X642499Y1987050D03*
X660999Y7050D03*
X674999Y20550D03*
X675499Y42050D03*
Y74550D03*
X674999Y59050D03*
X675499Y89050D03*
Y103550D03*
Y121050D03*
X674999Y140550D03*
Y159550D03*
X675999Y180550D03*
X662499Y218050D03*
X656499Y307050D03*
Y324550D03*
X655999Y344050D03*
X659899Y363250D03*
X666999Y476550D03*
Y491050D03*
Y508550D03*
X666499Y528050D03*
Y547050D03*
X667499Y568050D03*
X674999Y601550D03*
X665999Y623550D03*
X673999Y645150D03*
X665499Y766550D03*
X664999Y786050D03*
Y805050D03*
X665999Y826050D03*
X663999Y844550D03*
Y876550D03*
Y859050D03*
X663499Y896050D03*
Y915050D03*
X664499Y936050D03*
X658999Y959050D03*
X656999Y977550D03*
Y992050D03*
X673999Y1017550D03*
X656999Y1009550D03*
X673999Y1036550D03*
X656499Y1029050D03*
X674699Y1061450D03*
X656499Y1048050D03*
X674699Y1080450D03*
X669499Y1116550D03*
X674999Y1134950D03*
X667199Y1152850D03*
X668199Y1173850D03*
X670199Y1192750D03*
X671199Y1213750D03*
X668699Y1227650D03*
X657099Y1272850D03*
X657799Y1288450D03*
X672999Y1303450D03*
X656399Y1307050D03*
X671999Y1324950D03*
X665699Y1337250D03*
X654999Y1385050D03*
X659699Y1445950D03*
X665699Y1462250D03*
X656099Y1479550D03*
X672399Y1508750D03*
X673699Y1535350D03*
X662099Y1549650D03*
X670699Y1603150D03*
X671399Y1625350D03*
X657099Y1668850D03*
X674999Y1676550D03*
X656499Y1697050D03*
X675499Y1738050D03*
X665399Y1752350D03*
X675499Y1757050D03*
X675999Y1769050D03*
X659159Y1792278D03*
X659549Y1815384D03*
X667999Y1870950D03*
X669399Y1855350D03*
X674899Y1892350D03*
X661299Y1890050D03*
X674899Y1911350D03*
X661299Y1909050D03*
X674899Y1920350D03*
X661299Y1918050D03*
X673899Y1938850D03*
X660299Y1936550D03*
Y1955550D03*
X673899Y1966850D03*
Y1957850D03*
X660299Y1964550D03*
X659299Y1976250D03*
X661999Y1986550D03*
X680499Y6550D03*
X694999Y62650D03*
Y81650D03*
X695999Y102650D03*
X688999Y196550D03*
X677999Y218050D03*
X683499Y263050D03*
Y248550D03*
X680500Y280700D03*
X682999Y300050D03*
Y319050D03*
X683999Y340050D03*
X694999Y480550D03*
X695999Y501550D03*
X695499Y521050D03*
X691399Y548350D03*
X692399Y569350D03*
X691899Y588850D03*
X690499Y623050D03*
X693999Y648150D03*
X678499Y671050D03*
X679299Y703050D03*
X678499Y688550D03*
X681899Y713650D03*
X696299Y741850D03*
X694599Y763450D03*
X685999Y780050D03*
X687099Y804650D03*
Y823650D03*
X688099Y844650D03*
X687099Y896350D03*
Y915350D03*
X688099Y936350D03*
X678299Y978350D03*
Y997350D03*
X694999Y993050D03*
X692999Y1011550D03*
Y1026050D03*
Y1043550D03*
X692499Y1063050D03*
Y1082050D03*
X689999Y1105550D03*
X695999Y1203050D03*
Y1235050D03*
Y1217550D03*
X684299Y1249550D03*
X695999Y1323350D03*
X677999Y1347550D03*
X694999Y1360050D03*
X680299Y1365850D03*
X694999Y1379050D03*
X681299Y1393150D03*
X692999Y1406550D03*
X694999Y1388050D03*
X678299Y1425050D03*
X692999Y1421050D03*
X686999Y1468850D03*
X685299Y1551950D03*
X681299Y1579150D03*
X693599Y1602450D03*
X686699Y1638650D03*
X691999Y1660550D03*
X693099Y1722350D03*
X690499Y1744950D03*
X694599Y1768450D03*
X693549Y1793134D03*
X686473Y1818375D03*
X686999Y1870250D03*
X690899Y1855850D03*
X696299Y1898850D03*
X676399Y1901150D03*
X695299Y1926450D03*
X685499Y1940050D03*
X696299Y1976250D03*
X678799Y1975750D03*
X685499Y1959050D03*
Y1968050D03*
X679499Y1987050D03*
X697999Y7050D03*
X712499Y6050D03*
X699699Y141750D03*
Y160750D03*
X700699Y181750D03*
X711999Y218050D03*
X711499Y252550D03*
X711999Y307550D03*
Y293050D03*
Y325050D03*
X711499Y344550D03*
X712699Y434450D03*
X713699Y455450D03*
X713199Y474950D03*
Y489450D03*
X712599Y521050D03*
X713599Y542050D03*
X713099Y561550D03*
X699999Y610050D03*
X717099Y636050D03*
X702999Y656050D03*
Y688050D03*
Y670550D03*
X710899Y751150D03*
X716599Y736850D03*
X706999Y792550D03*
X707499Y773050D03*
X706999Y811550D03*
X707999Y832550D03*
X705999Y851050D03*
Y865550D03*
X707399Y899550D03*
Y918550D03*
X706499Y942550D03*
X713999Y1017050D03*
Y1031550D03*
X713499Y1068550D03*
X713999Y1049050D03*
X709999Y1105550D03*
X700499Y1118550D03*
X704299Y1132650D03*
X716999Y1148150D03*
X697499Y1153550D03*
X717999Y1169150D03*
X697499Y1172550D03*
X713399Y1178750D03*
X697999Y1184550D03*
X713599Y1214650D03*
X714399Y1199750D03*
X708699Y1243550D03*
X709699Y1264550D03*
X707899Y1346250D03*
X702299Y1404450D03*
X713899Y1386450D03*
X716899Y1459850D03*
X700899Y1450250D03*
X716199Y1503050D03*
X714599Y1533950D03*
X708899Y1549250D03*
X698599Y1568550D03*
X706700Y1579900D03*
X717099Y1702450D03*
X702599Y1730550D03*
X715999Y1744050D03*
X709099Y1751850D03*
X715999Y1763050D03*
Y1772050D03*
X706549Y1793634D03*
X717000Y1812384D03*
X705000Y1811900D03*
X711500Y1817700D03*
X704300Y1828400D03*
X697999Y1844550D03*
X706399Y1855850D03*
X705599Y1891850D03*
X716599Y1918450D03*
X698299Y1948050D03*
X711899Y1944050D03*
X709199Y1962950D03*
X717999Y1987550D03*
X702499D03*
X729999Y6550D03*
X725499Y23550D03*
X725999Y45050D03*
X725499Y62050D03*
X725999Y77550D03*
Y92050D03*
Y106550D03*
X738199Y137450D03*
X725999Y124050D03*
X725499Y143550D03*
Y162550D03*
X726499Y183550D03*
X728899Y204550D03*
X729499Y218550D03*
X723200Y275500D03*
X737999Y467050D03*
X738999Y488050D03*
X738499Y507550D03*
Y539550D03*
Y522050D03*
X737999Y559050D03*
X731499Y572050D03*
Y586550D03*
Y604050D03*
X721499Y617550D03*
X729699Y640350D03*
X723499Y654850D03*
X739399Y688150D03*
X720899Y712250D03*
X732499Y729250D03*
X727099Y715050D03*
X733799Y761450D03*
X723999Y783350D03*
Y802350D03*
X724999Y823350D03*
X728499Y841850D03*
X729999Y862850D03*
Y881850D03*
X730999Y902850D03*
X723699Y936250D03*
Y955250D03*
X724699Y976250D03*
X734999Y1030550D03*
Y1045050D03*
Y1062550D03*
X727499Y1106050D03*
X737999Y1119050D03*
X720499Y1118550D03*
X727499Y1132650D03*
X737999Y1159550D03*
Y1187550D03*
Y1178550D03*
X735999Y1206050D03*
X725499Y1231650D03*
X735999Y1220550D03*
X725499Y1250650D03*
X723499Y1278150D03*
X725499Y1259650D03*
X723499Y1292650D03*
X719199Y1322350D03*
X739199Y1348950D03*
X734199Y1373850D03*
X736199Y1399050D03*
X737799Y1428350D03*
X721899Y1419050D03*
X719499Y1446650D03*
X729199Y1492750D03*
X735799Y1533650D03*
X734499Y1563550D03*
X722199Y1564250D03*
X719999Y1605050D03*
X732999Y1620050D03*
X738799Y1677250D03*
X727399Y1694350D03*
X739199Y1716750D03*
X721199Y1723750D03*
X729999Y1756450D03*
X729499Y1778750D03*
X728099Y1844750D03*
X723199Y1867950D03*
X725899Y1855350D03*
X732999Y1868550D03*
X728299Y1888850D03*
X732199Y1878750D03*
X728799Y1908150D03*
Y1933050D03*
X736799Y1919450D03*
X730499Y1954650D03*
X721499Y1974550D03*
X737499Y1987050D03*
X749499Y6550D03*
X751499Y48350D03*
X757499Y44050D03*
Y63050D03*
X758499Y84050D03*
X752099Y112150D03*
X749499Y218550D03*
X749899Y398550D03*
X750899Y419550D03*
X750399Y453550D03*
Y439050D03*
X755199Y488150D03*
X756199Y509150D03*
X755699Y528650D03*
X754499Y564650D03*
X755499Y585650D03*
X754999Y605150D03*
X744999Y626550D03*
X757400Y686300D03*
X747999Y670750D03*
X754999Y694050D03*
X749999Y700050D03*
X749799Y767450D03*
X743099Y785350D03*
X751999Y817050D03*
X751499Y855550D03*
Y836550D03*
X751599Y887350D03*
Y906350D03*
X752599Y927350D03*
X749999Y946550D03*
Y965550D03*
X751399Y1004550D03*
X750999Y986550D03*
X751399Y1023550D03*
X752399Y1052550D03*
X753999Y1100050D03*
X758799Y1171150D03*
Y1190150D03*
Y1199150D03*
X756799Y1232150D03*
Y1217650D03*
X757399Y1258650D03*
Y1239650D03*
X740499Y1252550D03*
X757399Y1267650D03*
X740499Y1270050D03*
X740799Y1298750D03*
X755399Y1300650D03*
Y1286150D03*
X742099Y1320650D03*
X754999Y1420050D03*
Y1437550D03*
X741099Y1450250D03*
Y1498150D03*
X747199Y1509150D03*
X755499Y1507550D03*
Y1568550D03*
X743400Y1578700D03*
X751300Y1604900D03*
X756299Y1679050D03*
X750099Y1694950D03*
X756499Y1712150D03*
X747499Y1734350D03*
X751899Y1752150D03*
X747799Y1766750D03*
X744049Y1791634D03*
X740549Y1802634D03*
X753949Y1798194D03*
X740549Y1810384D03*
X747599Y1844250D03*
X744699Y1868450D03*
X758399Y1868350D03*
X743399Y1855850D03*
X743799Y1888850D03*
X753699Y1879250D03*
X755299Y1902150D03*
X739799D03*
X755500Y1914500D03*
X746499Y1974250D03*
X754999Y1987550D03*
X764999Y6550D03*
X763399Y24150D03*
X774399Y54050D03*
X775399Y80250D03*
X778399Y105250D03*
X767399Y140150D03*
X760799Y181950D03*
X779399Y200550D03*
X766999Y219050D03*
X781478Y363924D03*
X776978D03*
X772478Y359924D03*
Y363924D03*
X774999Y476550D03*
Y462050D03*
Y494050D03*
X774499Y513550D03*
Y532550D03*
X775499Y553550D03*
X777499Y638050D03*
X764599Y655750D03*
X777499Y664550D03*
X771800Y686600D03*
X766499Y699050D03*
Y705550D03*
X771196Y764382D03*
Y760382D03*
X775696Y764382D03*
X780196D03*
X778999Y806950D03*
X763099Y796350D03*
X775199Y839250D03*
Y858250D03*
X776199Y879250D03*
X772199Y920650D03*
Y939650D03*
X773199Y960650D03*
X776899Y988050D03*
Y1007050D03*
X777899Y1028050D03*
X760999Y1095550D03*
X773499Y1101050D03*
X769499D03*
X773499Y1105050D03*
X769499D03*
X780333Y1165892D03*
X775833D03*
X771333Y1161892D03*
Y1165892D03*
X762499Y1335550D03*
X779399Y1361850D03*
X762499Y1353050D03*
X773999Y1393450D03*
X763399Y1401450D03*
X769300Y1488100D03*
X779000Y1488400D03*
X771399Y1474550D03*
X770999Y1500050D03*
X780499D03*
X773499Y1509050D03*
X769499D03*
X778327Y1569796D03*
X773327Y1565796D03*
X773827Y1569796D03*
X768500Y1577500D03*
X776999Y1647650D03*
X765099Y1664950D03*
X770399Y1699650D03*
X779999Y1717050D03*
X770099Y1730350D03*
X779899Y1748150D03*
X765600Y1756800D03*
X765099Y1844750D03*
X779699Y1867950D03*
X779399Y1855850D03*
X763899D03*
X780799Y1888850D03*
X763299Y1888350D03*
X769199Y1879250D03*
X774499Y1908050D03*
X765999D03*
X775999Y1916050D03*
X768499Y1917550D03*
X775814Y1975699D03*
X770814Y1971713D03*
X771814Y1975713D03*
X777499Y1987550D03*
X784499Y6050D03*
X801999Y6550D03*
X796999Y27050D03*
X797499Y48550D03*
X796999Y65550D03*
X797499Y81050D03*
Y95550D03*
Y110050D03*
X796599Y123450D03*
X797499Y127550D03*
X796999Y147050D03*
Y166050D03*
X797999Y187050D03*
X786499Y219050D03*
X800999Y216550D03*
X784478Y355424D03*
Y359924D03*
X789999Y570050D03*
Y602050D03*
Y584550D03*
X785499Y641050D03*
X794999Y664550D03*
X786500Y686100D03*
X798000Y686400D03*
X782999Y699550D03*
X799385Y761436D03*
X783196Y760382D03*
Y755882D03*
X802499Y814550D03*
X801999Y834050D03*
Y853050D03*
X800999Y892550D03*
Y907050D03*
Y924550D03*
X800499Y944050D03*
Y963050D03*
X801499Y984050D03*
X800999Y1005550D03*
Y1020050D03*
Y1037550D03*
X783999Y1096550D03*
X789499Y1099550D03*
X783333Y1157392D03*
Y1161892D03*
X790999Y1194550D03*
Y1175550D03*
X791499Y1206550D03*
X789499Y1225050D03*
Y1257050D03*
Y1239550D03*
X788999Y1278150D03*
X791999Y1294450D03*
X795299Y1326650D03*
X799999Y1340550D03*
X798299Y1344250D03*
X799999Y1358050D03*
X781999Y1434650D03*
X786500Y1488600D03*
X801300Y1489000D03*
X786999Y1506550D03*
X785827Y1561296D03*
Y1565796D03*
X782827Y1569796D03*
X797299Y1646650D03*
X802899Y1670550D03*
X782999Y1668050D03*
Y1687050D03*
X783499Y1699050D03*
X794499Y1734550D03*
X787900Y1758800D03*
X801099Y1844750D03*
X785599D03*
X791799Y1855850D03*
X797199Y1868450D03*
X788699Y1878750D03*
X783499Y1907050D03*
X790499Y1913050D03*
X783814Y1967213D03*
Y1971713D03*
X784016Y1975708D03*
X789299Y1983850D03*
X792999Y1987550D03*
X818999Y6050D03*
X817599Y43750D03*
X813299Y49350D03*
Y68350D03*
X814299Y89350D03*
X813299Y110850D03*
X821199Y137450D03*
X805899Y126150D03*
X821499Y314050D03*
X819299Y413250D03*
Y394250D03*
X820299Y434250D03*
X802999Y466050D03*
X803999Y487050D03*
X803499Y506550D03*
Y538550D03*
Y521050D03*
X802999Y558050D03*
X814499Y569550D03*
Y601550D03*
Y584050D03*
X809700Y686300D03*
X806300Y670600D03*
X811499Y767550D03*
Y782050D03*
Y799550D03*
X802999Y874050D03*
X808299Y1175850D03*
X806599Y1189750D03*
X803599Y1211050D03*
X810199Y1229350D03*
Y1248350D03*
Y1257350D03*
X808199Y1275850D03*
Y1290350D03*
X822199Y1335250D03*
X819199Y1353550D03*
X806499Y1390550D03*
X803299Y1426650D03*
X806499Y1408050D03*
X805899Y1464250D03*
X813300Y1604100D03*
X803599Y1618350D03*
X814599Y1642650D03*
X823499Y1674050D03*
X808899Y1698450D03*
X823499Y1693050D03*
Y1702050D03*
X824100Y1719900D03*
X819400Y1721900D03*
X819200Y1727100D03*
X808299Y1755250D03*
X809299Y1856350D03*
X818900Y1870800D03*
X806199Y1879250D03*
X813599Y1979950D03*
X812499Y1987050D03*
X836499Y6550D03*
X824899Y25150D03*
X844799Y19850D03*
X839999Y46050D03*
X840499Y55050D03*
X840999Y62550D03*
X841499Y71550D03*
X837499Y138550D03*
X838499Y145050D03*
X838999Y313550D03*
X838499Y352050D03*
X839299Y390950D03*
Y409950D03*
X840299Y430950D03*
X824899Y500450D03*
X825899Y521450D03*
X825399Y540950D03*
X834599Y543050D03*
X835599Y564050D03*
X835099Y583550D03*
X841000Y671100D03*
X836149Y714050D03*
X835999Y767050D03*
X837799Y754150D03*
X835999Y781550D03*
Y799050D03*
X825199Y850850D03*
X827699Y873450D03*
Y892450D03*
X828699Y913450D03*
X826999Y963150D03*
Y982150D03*
X827999Y1003150D03*
X841999Y1118550D03*
X836149D03*
X839999Y1157550D03*
X831499Y1181550D03*
Y1209550D03*
Y1200550D03*
X829499Y1228050D03*
Y1242550D03*
X828199Y1267850D03*
X826199Y1294450D03*
X831499Y1324950D03*
X841999Y1341050D03*
Y1358550D03*
X825500Y1379000D03*
X834499Y1397550D03*
X836600Y1416500D03*
X843999Y1523550D03*
X839499D03*
X839899Y1562050D03*
X825999Y1578050D03*
X826499Y1609050D03*
X827199Y1622750D03*
X841499Y1638950D03*
X837199Y1660550D03*
X839199Y1683550D03*
X842799Y1701150D03*
X829200Y1719800D03*
X844499Y1788050D03*
X842500Y1799000D03*
X827999Y1791550D03*
X829799Y1856350D03*
X833199Y1868450D03*
X842199Y1879250D03*
X833100Y1878500D03*
X843999Y1928550D03*
X838999D03*
X840999Y1970550D03*
X829499Y1980250D03*
X829999Y1987550D03*
X855999Y6550D03*
X860799Y24150D03*
X865499Y39550D03*
X854499D03*
X856499Y71050D03*
X853999Y132550D03*
X849999Y145550D03*
X863999Y313550D03*
X858400Y352300D03*
X847999Y352550D03*
X854499Y387550D03*
Y373050D03*
Y405050D03*
X853999Y424550D03*
Y443550D03*
X854999Y464550D03*
X860199Y525050D03*
X861199Y546050D03*
X860699Y565550D03*
X861800Y591200D03*
X860499Y607550D03*
X860796Y678632D03*
X859999Y713050D03*
Y767550D03*
X856299Y753150D03*
X846799Y754150D03*
X865000Y752100D03*
X859999Y782050D03*
Y799550D03*
X847799Y828250D03*
X857099Y873450D03*
X866199Y920350D03*
Y901350D03*
X850999Y962550D03*
Y943550D03*
X851999Y983550D03*
X859999Y1118550D03*
X846499Y1170450D03*
X856400Y1157700D03*
X848999Y1158050D03*
X863300Y1153800D03*
X845799Y1190450D03*
X849799Y1199750D03*
X851999Y1237550D03*
Y1218550D03*
X852499Y1249550D03*
X850499Y1268050D03*
X860099Y1295450D03*
X850499Y1300050D03*
Y1282550D03*
X861999Y1522550D03*
X850099Y1572250D03*
X858400Y1561900D03*
X850499Y1562050D03*
X865300Y1557700D03*
X864000Y1578200D03*
X849900Y1605100D03*
X852499Y1621350D03*
X855799Y1658250D03*
X855350Y1703201D03*
X864099Y1683550D03*
X853799Y1790850D03*
X863099Y1813150D03*
X862499Y1823550D03*
X854977Y1818994D03*
X861414Y1928550D03*
X864414Y1940050D03*
X850499Y1977950D03*
X856999Y1970050D03*
X849999Y1970550D03*
X865200Y1968000D03*
X864999Y1987050D03*
X849499D03*
X871499Y6550D03*
X885999Y21150D03*
X883999Y39050D03*
X881499Y70550D03*
X866999D03*
X872499Y133050D03*
X871499Y146050D03*
X871786Y218924D03*
Y203924D03*
X887400Y233555D03*
X871786Y233924D03*
X887400Y259700D03*
X879878Y247724D03*
X870600Y346700D03*
X875799Y386250D03*
Y405250D03*
X876799Y426250D03*
X884399Y443450D03*
Y462450D03*
X885399Y483450D03*
X870719Y609705D03*
X870773Y624705D03*
X870719Y639705D03*
X887401Y665000D03*
X881125Y652050D03*
X871786Y679436D03*
Y709482D03*
X871499Y689436D03*
X866499Y724550D03*
X871385Y719436D03*
X884499Y767050D03*
Y781550D03*
Y799050D03*
X873999Y830550D03*
Y845050D03*
Y862550D03*
X886999Y907350D03*
X867199Y941350D03*
X886999Y947250D03*
X870777Y1014948D03*
X870468Y1030227D03*
X886919Y1044478D03*
X870298Y1045227D03*
X880033Y1058592D03*
X887400Y1070600D03*
X871399Y1182850D03*
Y1201850D03*
Y1210850D03*
X869399Y1229350D03*
Y1243850D03*
X872099Y1268150D03*
X871399Y1291450D03*
X875399Y1322650D03*
X868499Y1392550D03*
Y1410050D03*
X871836Y1420460D03*
X886913Y1449010D03*
X871836Y1435460D03*
X879727Y1463696D03*
X871836Y1450460D03*
X887499Y1476050D03*
X873099Y1572550D03*
X886900Y1604100D03*
X866499Y1603050D03*
Y1612050D03*
X868099Y1635650D03*
X887299Y1620050D03*
X877699Y1646650D03*
X882999Y1678250D03*
X879200Y1698700D03*
X879900Y1709300D03*
X883900Y1709500D03*
X875900D03*
X882700Y1738300D03*
X886900Y1737900D03*
X872950Y1744401D03*
X866699Y1770950D03*
X879399Y1798150D03*
X869634Y1826876D03*
X871836Y1840972D03*
X887499Y1855550D03*
X869999Y1855972D03*
X887401Y1881500D03*
X879399Y1974550D03*
X873399Y1963650D03*
X868699Y1983250D03*
X884499Y1986550D03*
X890999Y6050D03*
X908499Y6550D03*
X902999Y22050D03*
X902499Y35050D03*
X905499Y56550D03*
X904999Y61550D03*
X904499Y74050D03*
X904999Y67550D03*
X889999Y132550D03*
X891999Y146050D03*
X906999Y243150D03*
Y224150D03*
X907999Y264150D03*
X906399Y295250D03*
Y314250D03*
X907399Y335250D03*
X904999Y370550D03*
Y385050D03*
Y402550D03*
X904499Y422050D03*
Y441050D03*
X905499Y462050D03*
X898999Y622050D03*
Y604550D03*
X894000Y642400D03*
X900999Y652550D03*
Y670050D03*
X895999Y702550D03*
Y720050D03*
X898499Y830050D03*
Y844550D03*
X889699Y876050D03*
X898499Y862050D03*
X897299Y1182450D03*
X887999Y1209350D03*
X892499Y1224550D03*
Y1252550D03*
Y1243550D03*
X890499Y1271050D03*
Y1285550D03*
X890999Y1336550D03*
Y1354050D03*
X894499Y1423550D03*
Y1441050D03*
X895499Y1488050D03*
X902759Y1509585D03*
X894499Y1522050D03*
Y1539550D03*
X907500Y1604000D03*
X895999Y1661250D03*
X903599Y1686850D03*
X893200Y1721300D03*
X902900Y1709800D03*
X893200Y1730000D03*
X903299Y1814750D03*
X894999Y1829050D03*
X905299Y1852650D03*
X894000Y1868452D03*
X900299Y1876950D03*
X897299Y1904150D03*
X907599Y1930050D03*
X897599Y1938750D03*
X904299Y1954950D03*
X901999Y1987050D03*
X923999Y6050D03*
X917499Y21550D03*
X909499D03*
X909999Y35550D03*
X916499Y36050D03*
X928499Y51550D03*
X920900Y54700D03*
X928999Y56050D03*
X928499Y60550D03*
X928999Y65550D03*
X913699Y484650D03*
Y503650D03*
X914699Y524650D03*
X918999Y641550D03*
Y656050D03*
Y673550D03*
X918499Y693050D03*
Y712050D03*
X921899Y744850D03*
X919499Y733050D03*
X921899Y759350D03*
Y776850D03*
X921399Y796350D03*
X922399Y836350D03*
X921399Y815350D03*
X920399Y854850D03*
Y869350D03*
Y886850D03*
X919899Y906350D03*
Y925350D03*
X920899Y946350D03*
X921499Y999050D03*
Y1013550D03*
Y1031050D03*
X920999Y1050550D03*
Y1069550D03*
X925499Y1103550D03*
X921999Y1090550D03*
X925499Y1118050D03*
Y1135550D03*
X924999Y1174050D03*
Y1155050D03*
X925999Y1195050D03*
Y1207050D03*
Y1221550D03*
Y1239050D03*
X925499Y1258550D03*
Y1277550D03*
X926499Y1298550D03*
X928499Y1325350D03*
X925999Y1365050D03*
Y1379550D03*
Y1397050D03*
X925499Y1416550D03*
Y1435550D03*
X926499Y1456550D03*
X924999Y1485550D03*
Y1471050D03*
Y1503050D03*
X914599Y1521650D03*
X924499Y1522550D03*
X910899Y1549250D03*
X924499Y1541550D03*
X909700Y1576400D03*
X925499Y1562550D03*
X925599Y1612050D03*
X923599Y1634350D03*
X908899Y1630050D03*
X914899Y1657550D03*
X922599Y1682150D03*
X911299Y1800850D03*
X928000Y1818500D03*
X922899Y1853650D03*
X914999Y1868050D03*
Y1887050D03*
X914899Y1912450D03*
X915499Y1899050D03*
X916599Y1942650D03*
X914899Y1972250D03*
X921499Y1986550D03*
X941499Y6550D03*
X929999Y32550D03*
X940499Y33050D03*
X945499Y33550D03*
X943499Y48050D03*
Y55050D03*
Y72550D03*
X942999Y61550D03*
Y66550D03*
X943499Y78050D03*
X939199Y142050D03*
X932499Y191550D03*
Y206050D03*
Y223550D03*
X931999Y243050D03*
Y262050D03*
X932999Y283050D03*
X933499Y304050D03*
Y318550D03*
Y336050D03*
X932999Y355550D03*
Y374550D03*
X933999Y395550D03*
X933499Y429550D03*
Y415050D03*
Y447050D03*
X932999Y466550D03*
Y485550D03*
X933999Y506550D03*
X935499Y539050D03*
Y524550D03*
Y556550D03*
X934999Y576050D03*
X950299Y599650D03*
X934999Y595050D03*
X950299Y614150D03*
X935999Y616050D03*
X950299Y631650D03*
X949799Y651150D03*
Y670150D03*
X950799Y691150D03*
X944499Y750050D03*
Y735550D03*
Y767550D03*
X943999Y787050D03*
Y806050D03*
X944999Y827050D03*
X942999Y845550D03*
Y877550D03*
Y860050D03*
X942499Y897050D03*
Y916050D03*
X943499Y937050D03*
X949299Y977450D03*
Y991950D03*
Y1009450D03*
X948799Y1047950D03*
Y1028950D03*
X949799Y1068950D03*
Y1080950D03*
X950699Y1107750D03*
Y1122250D03*
Y1139750D03*
X950199Y1159250D03*
Y1178250D03*
X950699Y1262750D03*
Y1281750D03*
X943799Y1342950D03*
Y1380850D03*
X944000Y1391900D03*
X946700Y1426500D03*
X944000Y1511300D03*
X943199Y1531650D03*
X933199Y1577550D03*
X944499Y1632650D03*
X940499Y1656950D03*
X941499Y1679550D03*
X931499Y1702050D03*
X949799Y1756250D03*
X941800Y1787700D03*
X941499Y1776250D03*
X934200Y1793500D03*
X932199Y1801850D03*
X937199Y1869950D03*
X937499Y1893850D03*
X938199Y1917150D03*
X947499Y1936050D03*
X930999Y1931050D03*
X945199Y1946350D03*
X930999Y1950050D03*
X946199Y1966650D03*
X931499Y1962050D03*
X930199Y1979550D03*
X936999Y1986550D03*
X960999Y6550D03*
X954799Y17850D03*
X965999Y47050D03*
Y56050D03*
Y64050D03*
X966499Y73050D03*
Y82050D03*
X968399Y137150D03*
X967399Y180350D03*
X958799Y167350D03*
X956099Y181350D03*
X952799Y199150D03*
Y213650D03*
Y231150D03*
X952299Y250650D03*
Y269650D03*
X953299Y290650D03*
X952799Y324650D03*
Y310150D03*
Y342150D03*
X952299Y361650D03*
Y380650D03*
X953299Y401650D03*
X954799Y434150D03*
Y419650D03*
Y451650D03*
X966199Y473350D03*
Y492350D03*
X951799Y489650D03*
X967199Y513350D03*
X951799Y504150D03*
Y521650D03*
X951299Y560150D03*
Y541150D03*
X966799Y566350D03*
X952299Y581150D03*
X966799Y585350D03*
X967799Y606350D03*
X969499Y639050D03*
Y653550D03*
Y671050D03*
X968999Y709550D03*
Y690550D03*
X969999Y730550D03*
Y744250D03*
Y758750D03*
Y776250D03*
X969499Y795750D03*
Y814750D03*
X970499Y835750D03*
Y847750D03*
Y862250D03*
X969999Y899250D03*
X970499Y879750D03*
X969999Y918250D03*
X970999Y939250D03*
X971999Y996550D03*
Y1011050D03*
Y1028550D03*
X971499Y1067050D03*
Y1048050D03*
X951199Y1211250D03*
Y1199250D03*
Y1225750D03*
Y1243250D03*
X951699Y1302750D03*
X965099Y1324350D03*
X952499Y1361850D03*
X964400Y1409700D03*
X972000Y1442000D03*
Y1437500D03*
X971700Y1448300D03*
X962500Y1436500D03*
Y1441000D03*
X952800Y1437500D03*
Y1442000D03*
X962200Y1447300D03*
X952500Y1448300D03*
X971500Y1467500D03*
X971700Y1457800D03*
Y1462300D03*
Y1452800D03*
X962000Y1466500D03*
X952300Y1467500D03*
X962200Y1451800D03*
X952500Y1452800D03*
X962200Y1456800D03*
Y1461300D03*
X952500Y1457800D03*
Y1462300D03*
X966000Y1475000D03*
X958800Y1472500D03*
X966000Y1479500D03*
Y1484000D03*
X958800Y1477000D03*
Y1481500D03*
X965700Y1489300D03*
X958500Y1486800D03*
X960200Y1495300D03*
X951500D03*
X960049Y1500300D03*
X951349D03*
X960049Y1504800D03*
X951349D03*
X966600Y1529100D03*
X961400Y1528700D03*
X961900Y1522400D03*
X967100Y1522800D03*
X962100Y1516000D03*
X967300Y1516400D03*
X961600Y1534400D03*
X972000Y1547500D03*
X966100D03*
X960900Y1547100D03*
X961400Y1540800D03*
X966600Y1541200D03*
X966800Y1534800D03*
X961600Y1552900D03*
X966800Y1553300D03*
X972000Y1566000D03*
X966100D03*
X960900Y1565600D03*
X961400Y1559300D03*
X966600Y1559700D03*
X961900Y1572400D03*
X967100Y1572800D03*
X966400Y1585500D03*
X961200Y1585100D03*
X961700Y1578800D03*
X966900Y1579200D03*
X966500Y1592000D03*
X961300Y1591600D03*
X966300Y1598400D03*
X961100Y1598000D03*
X960600Y1604300D03*
X971700Y1604700D03*
X965800D03*
X957799Y1646950D03*
X955499Y1690850D03*
X958799Y1715750D03*
X965349Y1742000D03*
X954499Y1783550D03*
X971000Y1803000D03*
X971500Y1871500D03*
X966799Y1892150D03*
X955499Y1893050D03*
Y1902050D03*
X954099Y1915450D03*
X955799Y1951950D03*
X971499Y1956050D03*
Y1937050D03*
X953799Y1977950D03*
X971499Y1965050D03*
X956499Y1986050D03*
X976499Y6550D03*
X974699Y21450D03*
X991399Y22450D03*
X977399Y44050D03*
X974699Y64650D03*
X991999Y56050D03*
X983099Y83650D03*
X977699Y109150D03*
X981099Y123450D03*
X988699Y174350D03*
X982999Y189050D03*
Y203550D03*
Y221050D03*
X982499Y240550D03*
Y259550D03*
X983499Y280550D03*
X983999Y301550D03*
Y316050D03*
Y333550D03*
X983499Y353050D03*
Y372050D03*
X983999Y412550D03*
X984499Y393050D03*
X983999Y427050D03*
Y444550D03*
X983499Y464050D03*
Y483050D03*
X984499Y504050D03*
X985999Y536550D03*
Y522050D03*
Y554050D03*
X985499Y573550D03*
Y592550D03*
X986499Y613550D03*
X992999Y894550D03*
Y913550D03*
X972499Y1088050D03*
X975999Y1101050D03*
Y1115550D03*
X975499Y1152550D03*
X975999Y1133050D03*
X975499Y1171550D03*
X976499Y1192550D03*
Y1204550D03*
Y1219050D03*
Y1236550D03*
X975999Y1256050D03*
Y1275050D03*
X976999Y1296050D03*
X975100Y1342600D03*
X976499Y1362550D03*
Y1377050D03*
X992500Y1397300D03*
X973500Y1483000D03*
Y1478500D03*
X973200Y1488300D03*
X973500Y1474000D03*
X972549Y1502300D03*
Y1506800D03*
X972700Y1497300D03*
X973200Y1516400D03*
X972500Y1529100D03*
X973000Y1522800D03*
X972700Y1534800D03*
X972500Y1541200D03*
X972700Y1553300D03*
X972500Y1559700D03*
X973000Y1572800D03*
X972300Y1585500D03*
X972800Y1579200D03*
X972400Y1592000D03*
X972200Y1598400D03*
X989999Y1718050D03*
X993299Y1734350D03*
X976600Y1757100D03*
X976399Y1772250D03*
Y1791150D03*
X974699Y1914450D03*
X991999Y1915750D03*
X992299Y1929050D03*
X980999Y1933350D03*
X987999Y1949050D03*
Y1971950D03*
X989999Y1962650D03*
X973999Y1986550D03*
X995999Y6050D03*
X1013499Y6550D03*
X1002699Y40050D03*
X1005299Y71350D03*
X994399Y101250D03*
X1010599Y115550D03*
X1005299Y179950D03*
Y194450D03*
Y211950D03*
X1004799Y231450D03*
Y250450D03*
X1005799Y271450D03*
X1005299Y305450D03*
Y290950D03*
Y322950D03*
X1004799Y342450D03*
Y361450D03*
X1005799Y382450D03*
X1007299Y400450D03*
Y432450D03*
Y414950D03*
X1000699Y463350D03*
Y482350D03*
X1001699Y503350D03*
X1003999Y526850D03*
X1003499Y546350D03*
Y565350D03*
X1004499Y586350D03*
X1005999Y618850D03*
Y604350D03*
Y636350D03*
X994999Y747550D03*
Y733050D03*
Y765050D03*
X994499Y784550D03*
Y803550D03*
X995499Y824550D03*
X993499Y857550D03*
Y843050D03*
Y875050D03*
X994499Y941550D03*
X993999Y934550D03*
X994499Y956050D03*
Y973550D03*
X993999Y993050D03*
Y1012050D03*
X994999Y1033050D03*
Y1045050D03*
X998599Y1110950D03*
Y1096450D03*
Y1128450D03*
X998099Y1147950D03*
Y1166950D03*
X999099Y1187950D03*
Y1214450D03*
Y1199950D03*
Y1231950D03*
X998599Y1251450D03*
Y1270450D03*
X999599Y1291450D03*
X996500Y1324800D03*
X1000700Y1358100D03*
X994200Y1421500D03*
X1008999Y1702450D03*
X1008599Y1716050D03*
X994999Y1748950D03*
X999999Y1775250D03*
X1009999Y1797450D03*
X993499Y1805550D03*
X1007599Y1818450D03*
X993499Y1824550D03*
X1003599Y1846650D03*
X993499Y1833550D03*
X1011299Y1860650D03*
X995699Y1858950D03*
X1001599Y1921450D03*
X1000999Y1946350D03*
X1002500Y1953500D03*
X1005000Y1980500D03*
X994999Y1986550D03*
X1022000Y15500D03*
X1020499Y50550D03*
X1020999Y33050D03*
Y70050D03*
Y85550D03*
Y105050D03*
X1020499Y122550D03*
X1020999Y158550D03*
X1021499Y141050D03*
Y178050D03*
Y193550D03*
Y213050D03*
X1020999Y230550D03*
Y252050D03*
X1020499Y269550D03*
X1020999Y304550D03*
Y289050D03*
Y324050D03*
X1020499Y341550D03*
Y391550D03*
X1020999Y374050D03*
Y411050D03*
Y426550D03*
Y446050D03*
X1020499Y463550D03*
X1021999Y486550D03*
X1021499Y504050D03*
X1021999Y539050D03*
Y523550D03*
Y558550D03*
X1021499Y576050D03*
X1020499Y623050D03*
X1020999Y605550D03*
Y642550D03*
Y658050D03*
Y677550D03*
X1020499Y695050D03*
X1020999Y720050D03*
X1020499Y737550D03*
X1020999Y772550D03*
Y757050D03*
Y792050D03*
X1020499Y809550D03*
Y828050D03*
X1019999Y845550D03*
X1020499Y865050D03*
Y880550D03*
X1019999Y917550D03*
X1020499Y900050D03*
X1019999Y934050D03*
X1019499Y951550D03*
X1019999Y971050D03*
Y986550D03*
X1019499Y1023550D03*
X1019999Y1006050D03*
Y1043050D03*
Y1058550D03*
X1020499Y1081550D03*
X1019999Y1099050D03*
X1020499Y1118550D03*
Y1134050D03*
X1019499Y1146050D03*
X1018999Y1163550D03*
X1019499Y1183050D03*
Y1198550D03*
X1016999Y1219050D03*
X1016499Y1236550D03*
X1016999Y1256050D03*
Y1271550D03*
X1016499Y1301050D03*
X1022599Y1322950D03*
X1023300Y1344400D03*
X1024300Y1365200D03*
Y1393600D03*
X1022299Y1715750D03*
X1016899Y1731650D03*
X1020299Y1746650D03*
X1015299Y1765950D03*
X1026899Y1768550D03*
X1022999Y1784550D03*
X1022499Y1802050D03*
X1022999Y1821550D03*
Y1837050D03*
X1020999Y1860050D03*
X1020499Y1877550D03*
X1020999Y1912550D03*
Y1897050D03*
X1017499Y1954550D03*
X1017999Y1937050D03*
X1023000Y1973000D03*
X1017999Y1987050D03*
G54D20*
X267498Y305114D03*
Y300114D03*
Y295114D03*
Y310114D03*
X268499Y701550D03*
Y706550D03*
Y716550D03*
Y711550D03*
X266999Y1512550D03*
X267349Y1518150D03*
Y1522550D03*
Y1527172D03*
X279998Y304114D03*
Y299614D03*
Y295114D03*
Y308614D03*
X280999Y701550D03*
Y705550D03*
Y717550D03*
X280433Y713590D03*
X279499Y1510550D03*
Y1515050D03*
X279075Y1525957D03*
X278567Y1529925D03*
X795526Y1909696D03*
X795493Y1913696D03*
X795501Y1917696D03*
X795499Y1922050D03*
X807936Y1914865D03*
Y1910365D03*
X807997Y1922865D03*
X808005Y1918865D03*
G54D15*
X37999Y611550D03*
X34999Y1595350D03*
X45800Y405200D03*
X80699Y1004450D03*
Y1000450D03*
X80999Y1836550D03*
X78999Y1891550D03*
X82999D03*
Y1887550D03*
X78999D03*
Y1896050D03*
X78433Y1900010D03*
X78999Y1904050D03*
X83499Y1896050D03*
X83433Y1904010D03*
X101499Y1072550D03*
X100999Y1101050D03*
X104999D03*
X100999Y1096550D03*
X103999Y1216863D03*
X102900Y1196050D03*
X103686Y1223863D03*
X98599Y1491350D03*
X100699Y1471050D03*
X83999Y1900050D03*
X98433Y1940510D03*
X98999Y1944550D03*
X102433Y1940555D03*
X103433Y1944510D03*
X108200Y963600D03*
X105999Y1085800D03*
X125900Y1091282D03*
X105006Y1096866D03*
X106999Y1194550D03*
X119399Y1298113D03*
X116499Y1328013D03*
X120507Y1328096D03*
X106999Y1454450D03*
X105749Y1712749D03*
X117499Y1706050D03*
X124433Y1908510D03*
X124999Y1912550D03*
X129999Y78050D03*
X127999Y99550D03*
Y425050D03*
Y421050D03*
Y429550D03*
X147300Y526700D03*
X140940Y561800D03*
X132499Y1094550D03*
X135850Y1322250D03*
X133090Y1699959D03*
X128749Y1703300D03*
X129999Y1908550D03*
X129433Y1912510D03*
X166999Y88050D03*
X166499Y83550D03*
Y79050D03*
X158499D03*
Y84050D03*
Y88550D03*
Y93550D03*
X166999Y92550D03*
X165499Y106050D03*
X166999Y97050D03*
X155999Y181050D03*
X152000Y520813D03*
X147590Y521500D03*
X156500Y554000D03*
X161999Y768050D03*
X152499Y810550D03*
Y816050D03*
Y820550D03*
Y825050D03*
X151999Y936550D03*
X152499Y931550D03*
X159186Y946117D03*
X151300Y1049300D03*
X169999Y103050D03*
X173500Y166315D03*
X187499Y531613D03*
Y536113D03*
X188999Y541113D03*
Y549613D03*
Y545613D03*
X175823Y1297070D03*
X179999Y1301550D03*
Y1292550D03*
X175499D03*
X179999Y1296613D03*
X175499Y1302113D03*
X179999Y1306050D03*
X175499Y1306113D03*
X181100Y1682700D03*
X193499Y541113D03*
Y549613D03*
X193999Y545550D03*
X219499Y939613D03*
X214999D03*
X219499Y926613D03*
X214999D03*
X219499Y948613D03*
Y943813D03*
X214999Y944113D03*
Y948613D03*
X226999Y1941050D03*
X249600Y1896800D03*
X272499Y1153050D03*
X268499D03*
X263999D03*
X259999Y1152992D03*
X269500Y1135500D03*
X271999Y1161550D03*
X267999D03*
X263499D03*
X259499D03*
X260999Y1503550D03*
X266999Y1915550D03*
Y1920050D03*
Y1924550D03*
Y1929050D03*
Y1933550D03*
X282500Y1135000D03*
X293999Y1933050D03*
X281999Y1918550D03*
Y1923550D03*
Y1928550D03*
X306999Y1932550D03*
X302499D03*
X298499D03*
X326301Y1766030D03*
X334999Y1797050D03*
X350499Y597300D03*
X342999Y1947409D03*
X342621Y1943409D03*
X376999Y65550D03*
Y70050D03*
X381499Y65550D03*
Y70050D03*
X544300Y1784638D03*
X557999Y322550D03*
Y326550D03*
X558099Y335050D03*
X557933Y331010D03*
X558499Y616050D03*
X554304Y615840D03*
X554499Y624550D03*
X558699D03*
X554499Y620050D03*
X558709Y620245D03*
X563499Y1486550D03*
Y1492050D03*
Y1497550D03*
Y1503550D03*
X645549Y1815134D03*
X644360Y1819137D03*
X707600Y1815600D03*
X732549Y1806634D03*
X733149Y1798634D03*
X733049Y1814134D03*
X757999Y154550D03*
Y159050D03*
X753999Y154550D03*
Y159050D03*
X755499Y314550D03*
X755346Y319149D03*
X751539Y313984D03*
X751499Y318050D03*
Y679148D03*
X749499Y716050D03*
X744999Y715550D03*
X749999Y720050D03*
X745499D03*
X757499Y1079550D03*
X755499Y1119050D03*
X749999Y1119550D03*
X748999Y1115550D03*
X748499Y1111550D03*
X757999Y1484050D03*
X751000Y1517000D03*
X757500Y1522500D03*
X751000Y1521000D03*
Y1525000D03*
X756900Y1766000D03*
X752900D03*
X751999Y1775550D03*
X756617Y1780067D03*
X752657Y1779496D03*
X755999Y1775550D03*
X753558Y1769946D03*
X757518Y1770517D03*
X758499Y1893550D03*
X767159Y1792364D03*
X773999Y1923550D03*
X767999Y1923050D03*
X774499Y1930050D03*
X768999D03*
X802499Y1951550D03*
X800431Y1941193D03*
X809940Y264940D03*
X808660Y667540D03*
X807000Y1072900D03*
X809960Y1478040D03*
X810900Y1882440D03*
X843499Y82550D03*
X838999Y85050D03*
X837999Y91050D03*
X838499Y107050D03*
Y99550D03*
X839499Y119050D03*
X855499Y82050D03*
X845999Y111050D03*
X865499Y125550D03*
X876999Y82050D03*
X867499D03*
X886499Y99550D03*
Y104550D03*
X875499Y125550D03*
X873499Y1356050D03*
X890459Y100116D03*
X890499Y104550D03*
X903999Y574378D03*
X900999Y979050D03*
X904814Y1789113D03*
X916499Y172550D03*
X950100Y1626100D03*
X987100Y1624900D03*
X981200Y1625800D03*
G54D17*
X78150Y28858D03*
Y178464D03*
Y434370D03*
Y583976D03*
Y839882D03*
Y989488D03*
Y1245394D03*
Y1395000D03*
Y1650906D03*
Y1800512D03*
X158071Y191614D03*
Y341220D03*
Y597126D03*
Y746732D03*
Y1002638D03*
Y1152244D03*
Y1408150D03*
Y1557756D03*
Y1813662D03*
Y1963268D03*
X886417Y191614D03*
Y341220D03*
Y597126D03*
Y746732D03*
Y1002638D03*
Y1152244D03*
Y1408150D03*
Y1557756D03*
Y1813662D03*
Y1963268D03*
G54D10*
X-38436Y23633D03*
X-36811Y1104775D03*
X-35919Y1969497D03*
X1072493Y21507D03*
X1075940Y1769358D03*
G54D12*
X29531Y309549D03*
Y1029510D03*
X17720Y1903132D03*
X271657Y267699D03*
Y673210D03*
Y1078722D03*
Y1484234D03*
Y1889746D03*
X994098Y149588D03*
Y673210D03*
Y1068880D03*
G54D13*
X9843Y353144D03*
Y717711D03*
Y762617D03*
Y875216D03*
Y1337396D03*
Y1701963D03*
Y1746869D03*
Y1859468D03*
G54D22*
X1019291Y1416024D03*
Y1694212D03*
G54D18*
X129921Y17716D03*
X994093Y1889751D03*
G54D19*
X130499Y1730050D03*
X128000Y1735000D03*
X144499Y1729550D03*
X139500Y1730500D03*
X133000Y1734500D03*
X167499Y1714113D03*
X162499D03*
X165499Y1730613D03*
X167999Y1726613D03*
X163499D03*
X172499Y1714050D03*
X170499Y1731050D03*
X172499Y1726613D03*
X227999Y178050D03*
X227499Y192050D03*
X227999Y187050D03*
Y182550D03*
X231999Y178050D03*
Y192050D03*
Y187050D03*
Y182550D03*
G54D21*
X796873Y307571D03*
Y303071D03*
Y298571D03*
Y294071D03*
X794331Y698353D03*
Y702853D03*
Y707353D03*
Y711853D03*
X802499Y1097566D03*
X798499D03*
X795999Y1509550D03*
Y1504550D03*
Y1518550D03*
Y1514050D03*
X809373Y307571D03*
Y297571D03*
Y292571D03*
X808999Y303050D03*
X806831Y701853D03*
Y706853D03*
X806999Y697050D03*
X806831Y711853D03*
X811499Y1097050D03*
X807499D03*
X807341Y1111216D03*
Y1101216D03*
X806999Y1106050D03*
X807341Y1116216D03*
X809245Y1508722D03*
Y1503722D03*
Y1518722D03*
X808999Y1513550D03*
%LPC*%
G75*
G54D23*
G01X-87137Y-139897D02*
Y-107897D01*
G01X-75137Y-123897D02*
G02I-12000J0D01*
G01X-80287D02*
G02I-6850J0D01*
G01X-71137D02*
X-103137D01*
G01X-71137Y-139897D02*
Y-219897D01*
G01D02*
X1129963D01*
G01X-71137Y-175397D02*
X1129963D01*
G01X-71137Y-139897D02*
X1129963D01*
G01X342463D02*
Y-219897D01*
G01X479963Y-139897D02*
Y-219897D01*
G01X594963Y-139897D02*
Y-219897D01*
G01X762463Y-139897D02*
Y-219897D01*
G01X932463Y-139897D02*
Y-219897D01*
G01X1129963Y-139897D02*
Y-219897D01*
G01X1157963Y-123897D02*
G02I-12000J0D01*
G01X1152813D02*
G02I-6850J0D01*
G01X1161963D02*
X1129963D01*
G01X1145963Y-139897D02*
Y-107897D01*
G54D24*
G01X-53190Y-209897D02*
Y-192397D01*
G01X-44894D02*
X-53190Y-203189D01*
G01X-43584Y-209897D02*
X-49479Y-198231D01*
G01X-35909Y-209897D02*
Y-192397D01*
X-25865Y-209897D01*
Y-192397D01*
G01X-13387Y-209897D02*
X-15134Y-209605D01*
X-16662Y-208439D01*
X-17972Y-206689D01*
X-18846Y-204647D01*
X-19282Y-202314D01*
Y-199980D01*
X-18846Y-197647D01*
X-17972Y-195605D01*
X-16662Y-193856D01*
X-15134Y-192689D01*
X-13387Y-192397D01*
X-11641Y-192689D01*
X-10112Y-193856D01*
X-8802Y-195605D01*
X-7928Y-197647D01*
X-7492Y-199980D01*
Y-202314D01*
X-7928Y-204647D01*
X-8802Y-206689D01*
X-10112Y-208439D01*
X-11641Y-209605D01*
X-13387Y-209897D01*
G01X-472D02*
X8698Y-192397D01*
G01X-472D02*
X8698Y-209897D01*
G01X34310D02*
Y-192397D01*
X38676D01*
X40423Y-193272D01*
X41733Y-194439D01*
X42825Y-196188D01*
X43698Y-198231D01*
X43916Y-201147D01*
X43698Y-204064D01*
X42825Y-206106D01*
X41733Y-207856D01*
X40423Y-209022D01*
X38676Y-209897D01*
X34310D01*
G01X52246D02*
Y-192397D01*
X57705D01*
X59451Y-193272D01*
X60543Y-194439D01*
X60980Y-196772D01*
X60543Y-199106D01*
X59233Y-200564D01*
X57705Y-201439D01*
X52246D01*
G01X57705D02*
X60980Y-209897D01*
G01X71493Y-192397D02*
X76733D01*
G01X74113D02*
Y-209897D01*
G01X71493D02*
X76733D01*
G01X86154Y-192397D02*
X91613Y-209897D01*
X97072Y-192397D01*
G01X113480Y-209897D02*
X104746D01*
Y-192397D01*
X113480D01*
G01X109986Y-200855D02*
X104746D01*
G01X139746Y-209897D02*
Y-192397D01*
X144986D01*
X146733Y-193272D01*
X148043Y-195314D01*
X148480Y-197647D01*
X148043Y-199980D01*
X146951Y-201730D01*
X144986Y-202606D01*
X139746D01*
G01X157246Y-192397D02*
Y-209897D01*
X165980D01*
G01X173654D02*
X179113Y-192397D01*
X184572Y-209897D01*
G01X182606Y-203772D02*
X175619D01*
G01X191591Y-209897D02*
Y-192397D01*
X201635Y-209897D01*
Y-192397D01*
G01X218480Y-209897D02*
X209746D01*
Y-192397D01*
X218480D01*
G01X214986Y-200855D02*
X209746D01*
G01X250859Y-200564D02*
X251733Y-199689D01*
X252388Y-198231D01*
X252825Y-196188D01*
X252388Y-194439D01*
X251515Y-193272D01*
X249986Y-192397D01*
X244091D01*
Y-209897D01*
X251296D01*
X252825Y-208731D01*
X253698Y-206980D01*
X254135Y-204939D01*
X253698Y-202897D01*
X252388Y-201147D01*
X250859Y-200564D01*
X244091D01*
G01X266613Y-209897D02*
X264866Y-209605D01*
X263338Y-208439D01*
X262028Y-206689D01*
X261154Y-204647D01*
X260718Y-202314D01*
Y-199980D01*
X261154Y-197647D01*
X262028Y-195605D01*
X263338Y-193856D01*
X264866Y-192689D01*
X266613Y-192397D01*
X268359Y-192689D01*
X269888Y-193856D01*
X271198Y-195605D01*
X272072Y-197647D01*
X272508Y-199980D01*
Y-202314D01*
X272072Y-204647D01*
X271198Y-206689D01*
X269888Y-208439D01*
X268359Y-209605D01*
X266613Y-209897D01*
G01X278654D02*
X284113Y-192397D01*
X289572Y-209897D01*
G01X287606Y-203772D02*
X280619D01*
G01X297246Y-209897D02*
Y-192397D01*
X302705D01*
X304451Y-193272D01*
X305543Y-194439D01*
X305980Y-196772D01*
X305543Y-199106D01*
X304233Y-200564D01*
X302705Y-201439D01*
X297246D01*
G01X302705D02*
X305980Y-209897D01*
G01X314310D02*
Y-192397D01*
X318676D01*
X320423Y-193272D01*
X321733Y-194439D01*
X322825Y-196188D01*
X323698Y-198231D01*
X323916Y-201147D01*
X323698Y-204064D01*
X322825Y-206106D01*
X321733Y-207856D01*
X320423Y-209022D01*
X318676Y-209897D01*
X314310D01*
G01X94686Y-164897D02*
Y-147397D01*
X100363Y-161980D01*
X106040Y-147397D01*
Y-164897D01*
G01X117863D02*
X116553Y-164605D01*
X115243Y-163439D01*
X114369Y-161397D01*
X113933Y-159064D01*
X114369Y-156730D01*
X115243Y-154689D01*
X116553Y-153522D01*
X117863Y-153231D01*
X119173Y-153522D01*
X120483Y-154689D01*
X121356Y-156730D01*
X121575Y-159064D01*
X121356Y-161397D01*
X120483Y-163439D01*
X119173Y-164605D01*
X117863Y-164897D01*
G01X139293Y-147397D02*
Y-164897D01*
G01Y-162273D02*
X138420Y-163731D01*
X137109Y-164605D01*
X135581Y-164897D01*
X133835Y-164314D01*
X132525Y-162856D01*
X131651Y-161106D01*
X131433Y-159064D01*
X131651Y-157022D01*
X132525Y-155272D01*
X133835Y-153814D01*
X135581Y-153231D01*
X137109Y-153522D01*
X138201Y-154106D01*
X139293Y-155272D01*
G01X149588Y-157022D02*
X156575D01*
X155920Y-154980D01*
X154828Y-153814D01*
X153300Y-153231D01*
X151771Y-153522D01*
X150461Y-154397D01*
X149588Y-156439D01*
X149151Y-158189D01*
Y-159939D01*
X149588Y-161689D01*
X150680Y-163439D01*
X151990Y-164605D01*
X153518Y-164897D01*
X155046Y-164314D01*
X156575Y-162564D01*
G01X170363Y-164897D02*
Y-147397D01*
G01X376163Y-209897D02*
Y-192397D01*
X373543Y-195897D01*
G01Y-209897D02*
X378783D01*
G01X389515Y-195314D02*
X390825Y-193564D01*
X392353Y-192689D01*
X394100Y-192397D01*
X396283Y-192980D01*
X397811Y-194439D01*
X398248Y-196188D01*
X398030Y-197939D01*
X397156Y-199397D01*
X392790Y-202314D01*
X390825Y-204355D01*
X389515Y-207273D01*
X389078Y-209897D01*
X398248D01*
G01X413783D02*
Y-192397D01*
X405704Y-204939D01*
X416622D01*
G01X423860Y-206397D02*
X425169Y-208439D01*
X426916Y-209605D01*
X428881Y-209897D01*
X430628Y-209605D01*
X432375Y-208147D01*
X433466Y-206397D01*
X433685Y-204647D01*
X433248Y-202606D01*
X431720Y-201147D01*
X430191Y-200564D01*
X428226D01*
G01X430191D02*
X431501Y-199689D01*
X432593Y-198231D01*
X433030Y-196481D01*
X432593Y-194730D01*
X431501Y-193272D01*
X429536Y-192397D01*
X427571Y-192689D01*
X425606Y-193856D01*
G01X442015Y-195314D02*
X443325Y-193564D01*
X444853Y-192689D01*
X446600Y-192397D01*
X448783Y-192980D01*
X450311Y-194439D01*
X450748Y-196188D01*
X450530Y-197939D01*
X449656Y-199397D01*
X445290Y-202314D01*
X443325Y-204355D01*
X442015Y-207273D01*
X441578Y-209897D01*
X450748D01*
G01X363046Y-164897D02*
Y-147397D01*
X368286D01*
X370033Y-148272D01*
X371343Y-150314D01*
X371780Y-152647D01*
X371343Y-154980D01*
X370251Y-156730D01*
X368286Y-157606D01*
X363046D01*
G01X389716Y-148856D02*
X388406Y-147980D01*
X386878Y-147397D01*
X385131D01*
X383166Y-148272D01*
X381638Y-149730D01*
X380546Y-151481D01*
X379673Y-154397D01*
X379454Y-157022D01*
X379891Y-159647D01*
X380546Y-161397D01*
X381856Y-163147D01*
X383385Y-164314D01*
X384913Y-164897D01*
X386441D01*
X387970Y-164314D01*
X389280Y-163439D01*
X390372Y-162273D01*
G01X404159Y-155564D02*
X405033Y-154689D01*
X405688Y-153231D01*
X406125Y-151188D01*
X405688Y-149439D01*
X404815Y-148272D01*
X403286Y-147397D01*
X397391D01*
Y-164897D01*
X404596D01*
X406125Y-163731D01*
X406998Y-161980D01*
X407435Y-159939D01*
X406998Y-157897D01*
X405688Y-156147D01*
X404159Y-155564D01*
X397391D01*
G01X413363Y-170730D02*
X426463D01*
G01X432391Y-164897D02*
Y-147397D01*
X442435Y-164897D01*
Y-147397D01*
G01X454913Y-164897D02*
X453166Y-164605D01*
X451638Y-163439D01*
X450328Y-161689D01*
X449454Y-159647D01*
X449018Y-157314D01*
Y-154980D01*
X449454Y-152647D01*
X450328Y-150605D01*
X451638Y-148856D01*
X453166Y-147689D01*
X454913Y-147397D01*
X456659Y-147689D01*
X458188Y-148856D01*
X459498Y-150605D01*
X460372Y-152647D01*
X460808Y-154980D01*
Y-157314D01*
X460372Y-159647D01*
X459498Y-161689D01*
X458188Y-163439D01*
X456659Y-164605D01*
X454913Y-164897D01*
G01X505754Y-147397D02*
X511213Y-164897D01*
X516672Y-147397D01*
G01X533080Y-164897D02*
X524346D01*
Y-147397D01*
X533080D01*
G01X529586Y-155855D02*
X524346D01*
G01X541846Y-164897D02*
Y-147397D01*
X547305D01*
X549051Y-148272D01*
X550143Y-149439D01*
X550580Y-151772D01*
X550143Y-154106D01*
X548833Y-155564D01*
X547305Y-156439D01*
X541846D01*
G01X547305D02*
X550580Y-164897D01*
G01X563713Y-165480D02*
X563276Y-165189D01*
Y-164605D01*
X563713Y-164314D01*
X564150Y-164605D01*
Y-165189D01*
X563713Y-165480D01*
G01X537463Y-209897D02*
Y-192397D01*
X534843Y-195897D01*
G01Y-209897D02*
X540083D01*
G01X630546Y-147397D02*
Y-164897D01*
X639280D01*
G01X656343D02*
Y-153231D01*
G01Y-155272D02*
X655470Y-154106D01*
X654159Y-153522D01*
X652631Y-153231D01*
X651103Y-153814D01*
X649793Y-154980D01*
X648919Y-156730D01*
X648483Y-159064D01*
X648919Y-161397D01*
X649793Y-163147D01*
X651103Y-164314D01*
X652631Y-164897D01*
X654159Y-164605D01*
X655470Y-163731D01*
X656343Y-162564D01*
G01X665328Y-170147D02*
X666638Y-170730D01*
X668385Y-170147D01*
X669476Y-168981D01*
X670350Y-167522D01*
X671659Y-162856D01*
X674498Y-153231D01*
G01X667511D02*
X671659Y-162856D01*
G01X684138Y-157022D02*
X691125D01*
X690470Y-154980D01*
X689378Y-153814D01*
X687850Y-153231D01*
X686321Y-153522D01*
X685011Y-154397D01*
X684138Y-156439D01*
X683701Y-158189D01*
Y-159939D01*
X684138Y-161689D01*
X685230Y-163439D01*
X686540Y-164605D01*
X688068Y-164897D01*
X689596Y-164314D01*
X691125Y-162564D01*
G01X701856Y-164897D02*
Y-153231D01*
G01Y-155564D02*
X702948Y-154397D01*
X704040Y-153522D01*
X705568Y-153231D01*
X706659Y-153522D01*
X707970Y-154397D01*
G01X719138Y-162856D02*
X720230Y-164022D01*
X721758Y-164897D01*
X723068D01*
X724378Y-164314D01*
X725251Y-163439D01*
X725688Y-162273D01*
X725470Y-160522D01*
X724596Y-159647D01*
X720666Y-157897D01*
X719793Y-155855D01*
X720230Y-154397D01*
X721103Y-153522D01*
X722413Y-153231D01*
X723723Y-153522D01*
X725033Y-154397D01*
G01X639296Y-192397D02*
Y-209897D01*
X648030D01*
G01X663783D02*
Y-192397D01*
X655704Y-204939D01*
X666622D01*
G01X673204Y-192397D02*
X678663Y-209897D01*
X684122Y-192397D01*
G01X700966Y-193856D02*
X699656Y-192980D01*
X698128Y-192397D01*
X696381D01*
X694416Y-193272D01*
X692888Y-194730D01*
X691796Y-196481D01*
X690923Y-199397D01*
X690704Y-202022D01*
X691141Y-204647D01*
X691796Y-206397D01*
X693106Y-208147D01*
X694635Y-209314D01*
X696163Y-209897D01*
X697691D01*
X699220Y-209314D01*
X700530Y-208439D01*
X701622Y-207273D01*
G01X718466Y-193856D02*
X717156Y-192980D01*
X715628Y-192397D01*
X713881D01*
X711916Y-193272D01*
X710388Y-194730D01*
X709296Y-196481D01*
X708423Y-199397D01*
X708204Y-202022D01*
X708641Y-204647D01*
X709296Y-206397D01*
X710606Y-208147D01*
X712135Y-209314D01*
X713663Y-209897D01*
X715191D01*
X716720Y-209314D01*
X718030Y-208439D01*
X719122Y-207273D01*
G01X781410Y-164897D02*
Y-147397D01*
X785776D01*
X787523Y-148272D01*
X788833Y-149439D01*
X789925Y-151188D01*
X790798Y-153231D01*
X791016Y-156147D01*
X790798Y-159064D01*
X789925Y-161106D01*
X788833Y-162856D01*
X787523Y-164022D01*
X785776Y-164897D01*
X781410D01*
G01X800438Y-157022D02*
X807425D01*
X806770Y-154980D01*
X805678Y-153814D01*
X804150Y-153231D01*
X802621Y-153522D01*
X801311Y-154397D01*
X800438Y-156439D01*
X800001Y-158189D01*
Y-159939D01*
X800438Y-161689D01*
X801530Y-163439D01*
X802840Y-164605D01*
X804368Y-164897D01*
X805896Y-164314D01*
X807425Y-162564D01*
G01X817938Y-162856D02*
X819030Y-164022D01*
X820558Y-164897D01*
X821868D01*
X823178Y-164314D01*
X824051Y-163439D01*
X824488Y-162273D01*
X824270Y-160522D01*
X823396Y-159647D01*
X819466Y-157897D01*
X818593Y-155855D01*
X819030Y-154397D01*
X819903Y-153522D01*
X821213Y-153231D01*
X822523Y-153522D01*
X823833Y-154397D01*
G01X838713Y-153231D02*
Y-164897D01*
G01Y-148564D02*
X838276Y-148272D01*
Y-147689D01*
X838713Y-147397D01*
X839150Y-147689D01*
Y-148272D01*
X838713Y-148564D01*
G01X853156Y-169272D02*
X854685Y-170439D01*
X856431Y-170730D01*
X857959Y-170439D01*
X859270Y-168981D01*
X860143Y-166939D01*
Y-153231D01*
G01Y-155564D02*
X859270Y-154397D01*
X857959Y-153522D01*
X856431Y-153231D01*
X854685Y-153814D01*
X853593Y-154980D01*
X852719Y-157022D01*
X852283Y-159064D01*
X852501Y-160814D01*
X853375Y-162856D01*
X854685Y-164314D01*
X856431Y-164897D01*
X857741Y-164605D01*
X859270Y-163439D01*
X860143Y-162273D01*
G01X870001Y-164897D02*
Y-153231D01*
G01Y-156147D02*
X870875Y-154689D01*
X872185Y-153522D01*
X873931Y-153231D01*
X875459Y-153522D01*
X876770Y-154689D01*
X877425Y-156730D01*
Y-164897D01*
G01X887938Y-157022D02*
X894925D01*
X894270Y-154980D01*
X893178Y-153814D01*
X891650Y-153231D01*
X890121Y-153522D01*
X888811Y-154397D01*
X887938Y-156439D01*
X887501Y-158189D01*
Y-159939D01*
X887938Y-161689D01*
X889030Y-163439D01*
X890340Y-164605D01*
X891868Y-164897D01*
X893396Y-164314D01*
X894925Y-162564D01*
G01X905656Y-164897D02*
Y-153231D01*
G01Y-155564D02*
X906748Y-154397D01*
X907840Y-153522D01*
X909368Y-153231D01*
X910459Y-153522D01*
X911770Y-154397D01*
G01X825596Y-209897D02*
Y-192397D01*
X831055D01*
X832801Y-193272D01*
X833893Y-194439D01*
X834330Y-196772D01*
X833893Y-199106D01*
X832583Y-200564D01*
X831055Y-201439D01*
X825596D01*
G01X831055D02*
X834330Y-209897D01*
G01X847463D02*
X846153Y-209605D01*
X844843Y-208439D01*
X843969Y-206397D01*
X843533Y-204064D01*
X843969Y-201730D01*
X844843Y-199689D01*
X846153Y-198522D01*
X847463Y-198231D01*
X848773Y-198522D01*
X850083Y-199689D01*
X850956Y-201730D01*
X851175Y-204064D01*
X850956Y-206397D01*
X850083Y-208439D01*
X848773Y-209605D01*
X847463Y-209897D01*
G01X861033D02*
Y-192397D01*
G01Y-201147D02*
X862125Y-199397D01*
X863435Y-198522D01*
X864745Y-198231D01*
X866709Y-198814D01*
X868020Y-199980D01*
X868893Y-202022D01*
Y-204355D01*
X868456Y-206689D01*
X867583Y-208439D01*
X866055Y-209605D01*
X864745Y-209897D01*
X863435Y-209605D01*
X862125Y-208731D01*
X861033Y-207273D01*
G01X952413Y-209897D02*
Y-192397D01*
X949793Y-195897D01*
G01Y-209897D02*
X955033D01*
G01X969913Y-192397D02*
X968166Y-192980D01*
X966856Y-194439D01*
X965983Y-196188D01*
X965328Y-198522D01*
X965110Y-201147D01*
X965328Y-203772D01*
X965983Y-206106D01*
X966856Y-207856D01*
X968166Y-209314D01*
X969913Y-209897D01*
X971659Y-209314D01*
X972970Y-207856D01*
X973843Y-206106D01*
X974498Y-203772D01*
X974716Y-201147D01*
X974498Y-198522D01*
X973843Y-196188D01*
X972970Y-194439D01*
X971659Y-192980D01*
X969913Y-192397D01*
G01X983483Y-210480D02*
X991343Y-192397D01*
G01X1004913Y-209897D02*
Y-192397D01*
X1002293Y-195897D01*
G01Y-209897D02*
X1007533D01*
G01X1018265Y-202606D02*
X1019793Y-200564D01*
X1021103Y-199397D01*
X1022850Y-198814D01*
X1024378Y-199397D01*
X1025470Y-200564D01*
X1026343Y-202314D01*
X1026561Y-204355D01*
X1026343Y-206106D01*
X1025470Y-207856D01*
X1024159Y-209314D01*
X1022631Y-209897D01*
X1020885Y-209314D01*
X1019356Y-207564D01*
X1018483Y-204939D01*
X1018265Y-202022D01*
X1018701Y-198231D01*
X1019356Y-196188D01*
X1020448Y-194147D01*
X1021976Y-192689D01*
X1023505Y-192397D01*
X1025033Y-192980D01*
X1026125Y-194439D01*
G01X1035983Y-210480D02*
X1043843Y-192397D01*
G01X1053265Y-195314D02*
X1054575Y-193564D01*
X1056103Y-192689D01*
X1057850Y-192397D01*
X1060033Y-192980D01*
X1061561Y-194439D01*
X1061998Y-196188D01*
X1061780Y-197939D01*
X1060906Y-199397D01*
X1056540Y-202314D01*
X1054575Y-204355D01*
X1053265Y-207273D01*
X1052828Y-209897D01*
X1061998D01*
G01X1074913Y-192397D02*
X1073166Y-192980D01*
X1071856Y-194439D01*
X1070983Y-196188D01*
X1070328Y-198522D01*
X1070110Y-201147D01*
X1070328Y-203772D01*
X1070983Y-206106D01*
X1071856Y-207856D01*
X1073166Y-209314D01*
X1074913Y-209897D01*
X1076659Y-209314D01*
X1077970Y-207856D01*
X1078843Y-206106D01*
X1079498Y-203772D01*
X1079716Y-201147D01*
X1079498Y-198522D01*
X1078843Y-196188D01*
X1077970Y-194439D01*
X1076659Y-192980D01*
X1074913Y-192397D01*
G01X1092413Y-209897D02*
Y-192397D01*
X1089793Y-195897D01*
G01Y-209897D02*
X1095033D01*
G01X1105765Y-195314D02*
X1107075Y-193564D01*
X1108603Y-192689D01*
X1110350Y-192397D01*
X1112533Y-192980D01*
X1114061Y-194439D01*
X1114498Y-196188D01*
X1114280Y-197939D01*
X1113406Y-199397D01*
X1109040Y-202314D01*
X1107075Y-204355D01*
X1105765Y-207273D01*
X1105328Y-209897D01*
X1114498D01*
G01X1000110Y-164897D02*
Y-147397D01*
X1004476D01*
X1006223Y-148272D01*
X1007533Y-149439D01*
X1008625Y-151188D01*
X1009498Y-153231D01*
X1009716Y-156147D01*
X1009498Y-159064D01*
X1008625Y-161106D01*
X1007533Y-162856D01*
X1006223Y-164022D01*
X1004476Y-164897D01*
X1000110D01*
G01X1026343D02*
Y-153231D01*
G01Y-155272D02*
X1025470Y-154106D01*
X1024159Y-153522D01*
X1022631Y-153231D01*
X1021103Y-153814D01*
X1019793Y-154980D01*
X1018919Y-156730D01*
X1018483Y-159064D01*
X1018919Y-161397D01*
X1019793Y-163147D01*
X1021103Y-164314D01*
X1022631Y-164897D01*
X1024159Y-164605D01*
X1025470Y-163731D01*
X1026343Y-162564D01*
G01X1039913Y-147397D02*
Y-164897D01*
G01X1036856Y-153231D02*
X1042970D01*
G01X1054138Y-157022D02*
X1061125D01*
X1060470Y-154980D01*
X1059378Y-153814D01*
X1057850Y-153231D01*
X1056321Y-153522D01*
X1055011Y-154397D01*
X1054138Y-156439D01*
X1053701Y-158189D01*
Y-159939D01*
X1054138Y-161689D01*
X1055230Y-163439D01*
X1056540Y-164605D01*
X1058068Y-164897D01*
X1059596Y-164314D01*
X1061125Y-162564D01*
M02*
